(kicad_sch
	(version 20250114)
	(generator "eeschema")
	(generator_version "9.0")
	(paper "A3")
	(title_block
		(title "Antmicro Baseboard for Jetson AGX Thor")
		(date "2026-02-17")
		(rev "1.1.0")
		(company "Antmicro Ltd")
		(comment 1 "www.antmicro.com")
	)
	(text "Enable MUX"
		(exclude_from_sim no)
		(at 111.125 137.16 0)
		(effects
			(font
				(size 1.27 1.27)
			)
			(justify left bottom)
		)
	)
	(text "LOW: DFP role \nHIGH: NO ATTACH/UFP"
		(exclude_from_sim no)
		(at 250.19 119.38 0)
		(effects
			(font
				(size 1.27 1.27)
			)
			(justify left bottom)
		)
	)
	(text "10k - 3A\n500k - 1.5A\nDNP - 900mA"
		(exclude_from_sim no)
		(at 140.335 129.54 0)
		(effects
			(font
				(size 1.27 1.27)
			)
			(justify left bottom)
		)
	)
	(text "LOW: VCONN OC TRIP \nHIGH: NORMAL OPERATION"
		(exclude_from_sim no)
		(at 250.19 125.73 0)
		(effects
			(font
				(size 1.27 1.27)
			)
			(justify left bottom)
		)
	)
	(text "Both DNP - GPIO Mode\nHIGH - I2C Mode 0x67\nLOW -  I2C Mode 0x47"
		(exclude_from_sim no)
		(at 51.435 184.785 0)
		(effects
			(font
				(size 1.27 1.27)
			)
			(justify left bottom)
		)
	)
	(text "USB PORT 2"
		(exclude_from_sim no)
		(at 317.5 126.492 0)
		(effects
			(font
				(size 1.27 1.27)
				(thickness 0.254)
				(bold yes)
			)
		)
	)
	(text "Recovery USB Port 2\n"
		(exclude_from_sim no)
		(at 185.674 24.384 0)
		(effects
			(font
				(size 2.54 2.54)
				(thickness 0.508)
				(bold yes)
			)
		)
	)
	(text "Mode\nHIGH - DFP (HOST ONLY)\nLOW  - UFP (DEVICE ONLY)\nDNP  - DRP (DUAL ROLE PORT)\n"
		(exclude_from_sim no)
		(at 83.82 130.175 0)
		(effects
			(font
				(size 1.27 1.27)
			)
			(justify left bottom)
		)
	)
	(text "Enable CC controller"
		(exclude_from_sim no)
		(at 102.235 139.7 0)
		(effects
			(font
				(size 1.27 1.27)
			)
			(justify left bottom)
		)
	)
	(junction
		(at 280.67 162.56)
		(diameter 0)
		(color 0 0 0 0)
	)
	(junction
		(at 254 177.8)
		(diameter 0)
		(color 0 0 0 0)
	)
	(junction
		(at 218.44 90.17)
		(diameter 0)
		(color 0 0 0 0)
	)
	(junction
		(at 298.45 144.78)
		(diameter 0)
		(color 0 0 0 0)
	)
	(junction
		(at 217.17 119.38)
		(diameter 0)
		(color 0 0 0 0)
	)
	(junction
		(at 209.55 121.92)
		(diameter 0)
		(color 0 0 0 0)
	)
	(junction
		(at 261.62 167.64)
		(diameter 0)
		(color 0 0 0 0)
	)
	(junction
		(at 298.45 127)
		(diameter 0)
		(color 0 0 0 0)
	)
	(junction
		(at 287.02 147.32)
		(diameter 0)
		(color 0 0 0 0)
	)
	(junction
		(at 311.15 85.09)
		(diameter 0)
		(color 0 0 0 0)
	)
	(junction
		(at 227.33 114.3)
		(diameter 0)
		(color 0 0 0 0)
	)
	(junction
		(at 283.21 160.02)
		(diameter 0)
		(color 0 0 0 0)
	)
	(junction
		(at 113.03 186.69)
		(diameter 0)
		(color 0 0 0 0)
	)
	(junction
		(at 265.43 95.25)
		(diameter 0)
		(color 0 0 0 0)
	)
	(junction
		(at 284.48 134.62)
		(diameter 0)
		(color 0 0 0 0)
	)
	(junction
		(at 321.31 85.09)
		(diameter 0)
		(color 0 0 0 0)
	)
	(junction
		(at 289.56 144.78)
		(diameter 0)
		(color 0 0 0 0)
	)
	(junction
		(at 302.26 85.09)
		(diameter 0)
		(color 0 0 0 0)
	)
	(junction
		(at 299.72 193.04)
		(diameter 0)
		(color 0 0 0 0)
	)
	(junction
		(at 237.49 72.39)
		(diameter 0)
		(color 0 0 0 0)
	)
	(junction
		(at 240.03 90.17)
		(diameter 0)
		(color 0 0 0 0)
	)
	(junction
		(at 259.08 170.18)
		(diameter 0)
		(color 0 0 0 0)
	)
	(junction
		(at 82.55 181.61)
		(diameter 0)
		(color 0 0 0 0)
	)
	(junction
		(at 279.4 85.09)
		(diameter 0)
		(color 0 0 0 0)
	)
	(junction
		(at 281.94 132.08)
		(diameter 0)
		(color 0 0 0 0)
	)
	(junction
		(at 124.46 121.92)
		(diameter 0)
		(color 0 0 0 0)
	)
	(junction
		(at 256.54 175.26)
		(diameter 0)
		(color 0 0 0 0)
	)
	(junction
		(at 285.75 154.94)
		(diameter 0)
		(color 0 0 0 0)
	)
	(junction
		(at 299.72 147.32)
		(diameter 0)
		(color 0 0 0 0)
	)
	(junction
		(at 140.97 99.06)
		(diameter 0)
		(color 0 0 0 0)
	)
	(junction
		(at 124.46 139.7)
		(diameter 0)
		(color 0 0 0 0)
	)
	(junction
		(at 337.82 76.2)
		(diameter 0)
		(color 0 0 0 0)
	)
	(junction
		(at 298.45 85.09)
		(diameter 0)
		(color 0 0 0 0)
	)
	(junction
		(at 217.17 114.3)
		(diameter 0)
		(color 0 0 0 0)
	)
	(junction
		(at 288.29 152.4)
		(diameter 0)
		(color 0 0 0 0)
	)
	(junction
		(at 289.56 85.09)
		(diameter 0)
		(color 0 0 0 0)
	)
	(junction
		(at 237.49 90.17)
		(diameter 0)
		(color 0 0 0 0)
	)
	(junction
		(at 153.67 99.06)
		(diameter 0)
		(color 0 0 0 0)
	)
	(junction
		(at 162.56 99.06)
		(diameter 0)
		(color 0 0 0 0)
	)
	(no_connect
		(at 300.99 182.88)
	)
	(no_connect
		(at 300.99 185.42)
	)
	(bus_entry
		(at 269.24 147.32)
		(size -1.27 -1.27)
		(stroke
			(width 0)
			(type default)
		)
	)
	(bus_entry
		(at 267.97 143.51)
		(size 1.27 1.27)
		(stroke
			(width 0)
			(type default)
		)
	)
	(bus_entry
		(at 109.22 161.29)
		(size 1.27 1.27)
		(stroke
			(width 0)
			(type default)
		)
	)
	(bus_entry
		(at 113.03 168.91)
		(size 1.27 1.27)
		(stroke
			(width 0)
			(type default)
		)
	)
	(bus_entry
		(at 269.24 144.78)
		(size -1.27 -1.27)
		(stroke
			(width 0)
			(type default)
		)
	)
	(bus_entry
		(at 267.97 146.05)
		(size 1.27 1.27)
		(stroke
			(width 0)
			(type default)
		)
	)
	(bus_entry
		(at 109.22 153.67)
		(size 1.27 1.27)
		(stroke
			(width 0)
			(type default)
		)
	)
	(bus_entry
		(at 109.22 158.75)
		(size 1.27 1.27)
		(stroke
			(width 0)
			(type default)
		)
	)
	(bus_entry
		(at 113.03 171.45)
		(size 1.27 1.27)
		(stroke
			(width 0)
			(type default)
		)
	)
	(bus_entry
		(at 109.22 151.13)
		(size 1.27 1.27)
		(stroke
			(width 0)
			(type default)
		)
	)
	(wire
		(pts
			(xy 288.29 152.4) (xy 292.1 152.4)
		)
		(stroke
			(width 0)
			(type default)
		)
	)
	(wire
		(pts
			(xy 187.96 167.64) (xy 261.62 167.64)
		)
		(stroke
			(width 0)
			(type default)
		)
	)
	(wire
		(pts
			(xy 237.49 71.12) (xy 237.49 72.39)
		)
		(stroke
			(width 0)
			(type default)
		)
	)
	(wire
		(pts
			(xy 321.31 91.44) (xy 321.31 92.71)
		)
		(stroke
			(width 0)
			(type default)
		)
	)
	(wire
		(pts
			(xy 279.4 85.09) (xy 279.4 86.36)
		)
		(stroke
			(width 0)
			(type default)
		)
	)
	(wire
		(pts
			(xy 237.49 72.39) (xy 237.49 73.66)
		)
		(stroke
			(width 0)
			(type default)
		)
	)
	(wire
		(pts
			(xy 218.44 87.63) (xy 218.44 90.17)
		)
		(stroke
			(width 0)
			(type default)
		)
	)
	(wire
		(pts
			(xy 280.67 162.56) (xy 300.99 162.56)
		)
		(stroke
			(width 0)
			(type default)
		)
	)
	(wire
		(pts
			(xy 217.17 105.41) (xy 217.17 106.68)
		)
		(stroke
			(width 0)
			(type default)
		)
	)
	(wire
		(pts
			(xy 298.45 127) (xy 300.99 127)
		)
		(stroke
			(width 0)
			(type default)
		)
	)
	(wire
		(pts
			(xy 294.64 175.26) (xy 300.99 175.26)
		)
		(stroke
			(width 0)
			(type default)
		)
	)
	(wire
		(pts
			(xy 337.82 87.63) (xy 337.82 93.98)
		)
		(stroke
			(width 0)
			(type default)
		)
	)
	(wire
		(pts
			(xy 124.46 139.7) (xy 132.08 139.7)
		)
		(stroke
			(width 0)
			(type default)
		)
	)
	(wire
		(pts
			(xy 224.79 127) (xy 298.45 127)
		)
		(stroke
			(width 0)
			(type default)
		)
	)
	(wire
		(pts
			(xy 245.11 85.09) (xy 245.11 72.39)
		)
		(stroke
			(width 0)
			(type default)
		)
	)
	(wire
		(pts
			(xy 271.78 181.61) (xy 278.13 181.61)
		)
		(stroke
			(width 0)
			(type default)
		)
	)
	(wire
		(pts
			(xy 209.55 121.92) (xy 223.52 121.92)
		)
		(stroke
			(width 0)
			(type default)
		)
	)
	(wire
		(pts
			(xy 299.72 142.24) (xy 299.72 147.32)
		)
		(stroke
			(width 0)
			(type default)
		)
	)
	(wire
		(pts
			(xy 218.44 160.02) (xy 283.21 160.02)
		)
		(stroke
			(width 0)
			(type default)
		)
	)
	(wire
		(pts
			(xy 140.97 97.79) (xy 140.97 99.06)
		)
		(stroke
			(width 0)
			(type default)
		)
	)
	(wire
		(pts
			(xy 269.24 144.78) (xy 289.56 144.78)
		)
		(stroke
			(width 0)
			(type default)
		)
	)
	(wire
		(pts
			(xy 200.66 111.76) (xy 200.66 116.84)
		)
		(stroke
			(width 0)
			(type default)
		)
	)
	(bus
		(pts
			(xy 109.22 151.13) (xy 107.95 149.86)
		)
		(stroke
			(width 0)
			(type default)
		)
	)
	(wire
		(pts
			(xy 124.46 121.92) (xy 124.46 124.46)
		)
		(stroke
			(width 0)
			(type default)
		)
	)
	(wire
		(pts
			(xy 300.99 142.24) (xy 299.72 142.24)
		)
		(stroke
			(width 0)
			(type default)
		)
	)
	(wire
		(pts
			(xy 133.35 129.54) (xy 133.35 132.08)
		)
		(stroke
			(width 0)
			(type default)
		)
	)
	(wire
		(pts
			(xy 265.43 93.98) (xy 265.43 95.25)
		)
		(stroke
			(width 0)
			(type default)
		)
	)
	(wire
		(pts
			(xy 187.96 162.56) (xy 217.17 162.56)
		)
		(stroke
			(width 0)
			(type default)
		)
	)
	(wire
		(pts
			(xy 294.64 154.94) (xy 300.99 154.94)
		)
		(stroke
			(width 0)
			(type default)
		)
	)
	(wire
		(pts
			(xy 281.94 119.38) (xy 281.94 132.08)
		)
		(stroke
			(width 0)
			(type default)
		)
	)
	(wire
		(pts
			(xy 162.56 105.41) (xy 162.56 106.68)
		)
		(stroke
			(width 0)
			(type default)
		)
	)
	(wire
		(pts
			(xy 134.62 152.4) (xy 160.02 152.4)
		)
		(stroke
			(width 0)
			(type default)
		)
	)
	(wire
		(pts
			(xy 245.11 87.63) (xy 246.38 87.63)
		)
		(stroke
			(width 0)
			(type default)
		)
	)
	(wire
		(pts
			(xy 151.13 99.06) (xy 153.67 99.06)
		)
		(stroke
			(width 0)
			(type default)
		)
	)
	(wire
		(pts
			(xy 240.03 90.17) (xy 246.38 90.17)
		)
		(stroke
			(width 0)
			(type default)
		)
	)
	(wire
		(pts
			(xy 279.4 119.38) (xy 279.4 120.65)
		)
		(stroke
			(width 0)
			(type default)
		)
	)
	(wire
		(pts
			(xy 137.16 139.7) (xy 160.02 139.7)
		)
		(stroke
			(width 0)
			(type default)
		)
	)
	(wire
		(pts
			(xy 285.75 154.94) (xy 292.1 154.94)
		)
		(stroke
			(width 0)
			(type default)
		)
	)
	(wire
		(pts
			(xy 300.99 139.7) (xy 298.45 139.7)
		)
		(stroke
			(width 0)
			(type default)
		)
	)
	(wire
		(pts
			(xy 233.68 100.33) (xy 227.33 100.33)
		)
		(stroke
			(width 0)
			(type default)
		)
	)
	(wire
		(pts
			(xy 218.44 81.28) (xy 218.44 82.55)
		)
		(stroke
			(width 0)
			(type default)
		)
	)
	(wire
		(pts
			(xy 294.64 152.4) (xy 300.99 152.4)
		)
		(stroke
			(width 0)
			(type default)
		)
	)
	(wire
		(pts
			(xy 284.48 119.38) (xy 284.48 134.62)
		)
		(stroke
			(width 0)
			(type default)
		)
	)
	(wire
		(pts
			(xy 110.49 154.94) (xy 132.08 154.94)
		)
		(stroke
			(width 0)
			(type default)
		)
	)
	(wire
		(pts
			(xy 148.59 119.38) (xy 148.59 99.06)
		)
		(stroke
			(width 0)
			(type default)
		)
	)
	(wire
		(pts
			(xy 187.96 154.94) (xy 285.75 154.94)
		)
		(stroke
			(width 0)
			(type default)
		)
	)
	(wire
		(pts
			(xy 210.82 90.17) (xy 218.44 90.17)
		)
		(stroke
			(width 0)
			(type default)
		)
	)
	(wire
		(pts
			(xy 245.11 184.15) (xy 245.11 181.61)
		)
		(stroke
			(width 0)
			(type default)
		)
	)
	(wire
		(pts
			(xy 135.89 172.72) (xy 160.02 172.72)
		)
		(stroke
			(width 0)
			(type default)
		)
	)
	(wire
		(pts
			(xy 256.54 175.26) (xy 292.1 175.26)
		)
		(stroke
			(width 0)
			(type default)
		)
	)
	(wire
		(pts
			(xy 144.78 189.23) (xy 124.46 189.23)
		)
		(stroke
			(width 0)
			(type default)
		)
	)
	(wire
		(pts
			(xy 137.16 154.94) (xy 160.02 154.94)
		)
		(stroke
			(width 0)
			(type default)
		)
	)
	(wire
		(pts
			(xy 135.89 170.18) (xy 160.02 170.18)
		)
		(stroke
			(width 0)
			(type default)
		)
	)
	(wire
		(pts
			(xy 217.17 111.76) (xy 217.17 114.3)
		)
		(stroke
			(width 0)
			(type default)
		)
	)
	(wire
		(pts
			(xy 187.96 116.84) (xy 200.66 116.84)
		)
		(stroke
			(width 0)
			(type default)
		)
	)
	(wire
		(pts
			(xy 302.26 85.09) (xy 298.45 85.09)
		)
		(stroke
			(width 0)
			(type default)
		)
	)
	(wire
		(pts
			(xy 284.48 134.62) (xy 300.99 134.62)
		)
		(stroke
			(width 0)
			(type default)
		)
	)
	(wire
		(pts
			(xy 337.82 63.5) (xy 337.82 67.31)
		)
		(stroke
			(width 0)
			(type default)
		)
	)
	(wire
		(pts
			(xy 127 175.26) (xy 130.81 175.26)
		)
		(stroke
			(width 0)
			(type default)
		)
	)
	(wire
		(pts
			(xy 160.02 132.08) (xy 133.35 132.08)
		)
		(stroke
			(width 0)
			(type default)
		)
	)
	(wire
		(pts
			(xy 227.33 114.3) (xy 234.95 114.3)
		)
		(stroke
			(width 0)
			(type default)
		)
	)
	(wire
		(pts
			(xy 209.55 111.76) (xy 209.55 121.92)
		)
		(stroke
			(width 0)
			(type default)
		)
	)
	(wire
		(pts
			(xy 119.38 189.23) (xy 113.03 189.23)
		)
		(stroke
			(width 0)
			(type default)
		)
	)
	(wire
		(pts
			(xy 342.9 76.2) (xy 337.82 76.2)
		)
		(stroke
			(width 0)
			(type default)
		)
	)
	(wire
		(pts
			(xy 151.13 116.84) (xy 151.13 99.06)
		)
		(stroke
			(width 0)
			(type default)
		)
	)
	(wire
		(pts
			(xy 259.08 170.18) (xy 259.08 182.88)
		)
		(stroke
			(width 0)
			(type default)
		)
	)
	(wire
		(pts
			(xy 292.1 175.26) (xy 294.64 177.8)
		)
		(stroke
			(width 0)
			(type default)
		)
	)
	(wire
		(pts
			(xy 187.96 175.26) (xy 213.36 175.26)
		)
		(stroke
			(width 0)
			(type default)
		)
	)
	(wire
		(pts
			(xy 124.46 137.16) (xy 132.08 137.16)
		)
		(stroke
			(width 0)
			(type default)
		)
	)
	(wire
		(pts
			(xy 237.49 90.17) (xy 240.03 90.17)
		)
		(stroke
			(width 0)
			(type default)
		)
	)
	(wire
		(pts
			(xy 259.08 170.18) (xy 300.99 170.18)
		)
		(stroke
			(width 0)
			(type default)
		)
	)
	(wire
		(pts
			(xy 148.59 119.38) (xy 160.02 119.38)
		)
		(stroke
			(width 0)
			(type default)
		)
	)
	(wire
		(pts
			(xy 265.43 95.25) (xy 262.89 95.25)
		)
		(stroke
			(width 0)
			(type default)
		)
	)
	(polyline
		(pts
			(xy 83.82 120.65) (xy 83.82 132.08)
		)
		(stroke
			(width 0)
			(type default)
		)
	)
	(wire
		(pts
			(xy 187.96 152.4) (xy 288.29 152.4)
		)
		(stroke
			(width 0)
			(type default)
		)
	)
	(wire
		(pts
			(xy 269.24 147.32) (xy 287.02 147.32)
		)
		(stroke
			(width 0)
			(type default)
		)
	)
	(wire
		(pts
			(xy 135.89 175.26) (xy 160.02 175.26)
		)
		(stroke
			(width 0)
			(type default)
		)
	)
	(wire
		(pts
			(xy 261.62 87.63) (xy 265.43 87.63)
		)
		(stroke
			(width 0)
			(type default)
		)
	)
	(wire
		(pts
			(xy 160.02 116.84) (xy 151.13 116.84)
		)
		(stroke
			(width 0)
			(type default)
		)
	)
	(wire
		(pts
			(xy 137.16 162.56) (xy 160.02 162.56)
		)
		(stroke
			(width 0)
			(type default)
		)
	)
	(wire
		(pts
			(xy 148.59 99.06) (xy 140.97 99.06)
		)
		(stroke
			(width 0)
			(type default)
		)
	)
	(wire
		(pts
			(xy 289.56 119.38) (xy 289.56 144.78)
		)
		(stroke
			(width 0)
			(type default)
		)
	)
	(wire
		(pts
			(xy 113.03 184.15) (xy 113.03 186.69)
		)
		(stroke
			(width 0)
			(type default)
		)
	)
	(wire
		(pts
			(xy 158.75 179.07) (xy 158.75 181.61)
		)
		(stroke
			(width 0)
			(type default)
		)
	)
	(wire
		(pts
			(xy 133.35 121.92) (xy 133.35 124.46)
		)
		(stroke
			(width 0)
			(type default)
		)
	)
	(wire
		(pts
			(xy 124.46 121.92) (xy 133.35 121.92)
		)
		(stroke
			(width 0)
			(type default)
		)
	)
	(wire
		(pts
			(xy 289.56 85.09) (xy 289.56 86.36)
		)
		(stroke
			(width 0)
			(type default)
		)
	)
	(wire
		(pts
			(xy 162.56 97.79) (xy 162.56 99.06)
		)
		(stroke
			(width 0)
			(type default)
		)
	)
	(wire
		(pts
			(xy 280.67 162.56) (xy 280.67 182.88)
		)
		(stroke
			(width 0)
			(type default)
		)
	)
	(wire
		(pts
			(xy 245.11 181.61) (xy 251.46 181.61)
		)
		(stroke
			(width 0)
			(type default)
		)
	)
	(wire
		(pts
			(xy 110.49 162.56) (xy 132.08 162.56)
		)
		(stroke
			(width 0)
			(type default)
		)
	)
	(wire
		(pts
			(xy 124.46 139.7) (xy 124.46 140.97)
		)
		(stroke
			(width 0)
			(type default)
		)
	)
	(wire
		(pts
			(xy 279.4 85.09) (xy 289.56 85.09)
		)
		(stroke
			(width 0)
			(type default)
		)
	)
	(wire
		(pts
			(xy 158.75 179.07) (xy 160.02 179.07)
		)
		(stroke
			(width 0)
			(type default)
		)
	)
	(wire
		(pts
			(xy 240.03 87.63) (xy 237.49 87.63)
		)
		(stroke
			(width 0)
			(type default)
		)
	)
	(wire
		(pts
			(xy 124.46 137.16) (xy 124.46 139.7)
		)
		(stroke
			(width 0)
			(type default)
		)
	)
	(wire
		(pts
			(xy 209.55 105.41) (xy 209.55 106.68)
		)
		(stroke
			(width 0)
			(type default)
		)
	)
	(wire
		(pts
			(xy 321.31 85.09) (xy 321.31 86.36)
		)
		(stroke
			(width 0)
			(type default)
		)
	)
	(wire
		(pts
			(xy 251.46 181.61) (xy 251.46 182.88)
		)
		(stroke
			(width 0)
			(type default)
		)
	)
	(wire
		(pts
			(xy 287.02 119.38) (xy 287.02 147.32)
		)
		(stroke
			(width 0)
			(type default)
		)
	)
	(wire
		(pts
			(xy 289.56 85.09) (xy 298.45 85.09)
		)
		(stroke
			(width 0)
			(type default)
		)
	)
	(wire
		(pts
			(xy 222.25 177.8) (xy 254 177.8)
		)
		(stroke
			(width 0)
			(type default)
		)
	)
	(wire
		(pts
			(xy 294.64 177.8) (xy 300.99 177.8)
		)
		(stroke
			(width 0)
			(type default)
		)
	)
	(bus
		(pts
			(xy 113.03 168.91) (xy 111.76 167.64)
		)
		(stroke
			(width 0)
			(type default)
		)
	)
	(wire
		(pts
			(xy 144.78 186.69) (xy 124.46 186.69)
		)
		(stroke
			(width 0)
			(type default)
		)
	)
	(wire
		(pts
			(xy 114.3 170.18) (xy 130.81 170.18)
		)
		(stroke
			(width 0)
			(type default)
		)
	)
	(wire
		(pts
			(xy 110.49 152.4) (xy 129.54 152.4)
		)
		(stroke
			(width 0)
			(type default)
		)
	)
	(wire
		(pts
			(xy 261.62 85.09) (xy 279.4 85.09)
		)
		(stroke
			(width 0)
			(type default)
		)
	)
	(wire
		(pts
			(xy 82.55 187.96) (xy 82.55 189.23)
		)
		(stroke
			(width 0)
			(type default)
		)
	)
	(bus
		(pts
			(xy 267.97 143.51) (xy 266.7 142.24)
		)
		(stroke
			(width 0)
			(type default)
		)
	)
	(wire
		(pts
			(xy 321.31 97.79) (xy 321.31 99.06)
		)
		(stroke
			(width 0)
			(type default)
		)
	)
	(bus
		(pts
			(xy 109.22 158.75) (xy 109.22 161.29)
		)
		(stroke
			(width 0)
			(type default)
		)
	)
	(bus
		(pts
			(xy 105.41 149.86) (xy 107.95 149.86)
		)
		(stroke
			(width 0)
			(type default)
		)
	)
	(wire
		(pts
			(xy 231.14 90.17) (xy 237.49 90.17)
		)
		(stroke
			(width 0)
			(type default)
		)
	)
	(wire
		(pts
			(xy 265.43 95.25) (xy 265.43 96.52)
		)
		(stroke
			(width 0)
			(type default)
		)
	)
	(wire
		(pts
			(xy 82.55 173.99) (xy 82.55 175.26)
		)
		(stroke
			(width 0)
			(type default)
		)
	)
	(wire
		(pts
			(xy 240.03 102.87) (xy 240.03 104.14)
		)
		(stroke
			(width 0)
			(type default)
		)
	)
	(bus
		(pts
			(xy 109.22 151.13) (xy 109.22 153.67)
		)
		(stroke
			(width 0)
			(type default)
		)
	)
	(wire
		(pts
			(xy 292.1 177.8) (xy 294.64 175.26)
		)
		(stroke
			(width 0)
			(type default)
		)
	)
	(wire
		(pts
			(xy 114.3 172.72) (xy 130.81 172.72)
		)
		(stroke
			(width 0)
			(type default)
		)
	)
	(wire
		(pts
			(xy 82.55 181.61) (xy 82.55 182.88)
		)
		(stroke
			(width 0)
			(type default)
		)
	)
	(wire
		(pts
			(xy 140.97 105.41) (xy 140.97 106.68)
		)
		(stroke
			(width 0)
			(type default)
		)
	)
	(wire
		(pts
			(xy 124.46 120.65) (xy 124.46 121.92)
		)
		(stroke
			(width 0)
			(type default)
		)
	)
	(wire
		(pts
			(xy 299.72 190.5) (xy 300.99 190.5)
		)
		(stroke
			(width 0)
			(type default)
		)
	)
	(bus
		(pts
			(xy 109.22 153.67) (xy 109.22 158.75)
		)
		(stroke
			(width 0)
			(type default)
		)
	)
	(wire
		(pts
			(xy 321.31 85.09) (xy 331.47 85.09)
		)
		(stroke
			(width 0)
			(type default)
		)
	)
	(wire
		(pts
			(xy 187.96 132.08) (xy 281.94 132.08)
		)
		(stroke
			(width 0)
			(type default)
		)
	)
	(wire
		(pts
			(xy 200.66 105.41) (xy 200.66 106.68)
		)
		(stroke
			(width 0)
			(type default)
		)
	)
	(bus
		(pts
			(xy 113.03 168.91) (xy 113.03 171.45)
		)
		(stroke
			(width 0)
			(type default)
		)
	)
	(wire
		(pts
			(xy 124.46 129.54) (xy 124.46 134.62)
		)
		(stroke
			(width 0)
			(type default)
		)
	)
	(wire
		(pts
			(xy 311.15 85.09) (xy 321.31 85.09)
		)
		(stroke
			(width 0)
			(type default)
		)
	)
	(wire
		(pts
			(xy 113.03 189.23) (xy 113.03 186.69)
		)
		(stroke
			(width 0)
			(type default)
		)
	)
	(wire
		(pts
			(xy 187.96 127) (xy 219.71 127)
		)
		(stroke
			(width 0)
			(type default)
		)
	)
	(wire
		(pts
			(xy 153.67 99.06) (xy 153.67 100.33)
		)
		(stroke
			(width 0)
			(type default)
		)
	)
	(wire
		(pts
			(xy 337.82 72.39) (xy 337.82 76.2)
		)
		(stroke
			(width 0)
			(type default)
		)
	)
	(wire
		(pts
			(xy 254 177.8) (xy 292.1 177.8)
		)
		(stroke
			(width 0)
			(type default)
		)
	)
	(polyline
		(pts
			(xy 132.08 132.08) (xy 132.08 120.65)
		)
		(stroke
			(width 0)
			(type default)
		)
	)
	(wire
		(pts
			(xy 227.33 100.33) (xy 227.33 114.3)
		)
		(stroke
			(width 0)
			(type default)
		)
	)
	(bus
		(pts
			(xy 109.22 167.64) (xy 111.76 167.64)
		)
		(stroke
			(width 0)
			(type default)
		)
	)
	(wire
		(pts
			(xy 137.16 137.16) (xy 160.02 137.16)
		)
		(stroke
			(width 0)
			(type default)
		)
	)
	(wire
		(pts
			(xy 187.96 160.02) (xy 213.36 160.02)
		)
		(stroke
			(width 0)
			(type default)
		)
	)
	(wire
		(pts
			(xy 283.21 160.02) (xy 300.99 160.02)
		)
		(stroke
			(width 0)
			(type default)
		)
	)
	(wire
		(pts
			(xy 237.49 87.63) (xy 237.49 90.17)
		)
		(stroke
			(width 0)
			(type default)
		)
	)
	(wire
		(pts
			(xy 237.49 72.39) (xy 245.11 72.39)
		)
		(stroke
			(width 0)
			(type default)
		)
	)
	(wire
		(pts
			(xy 289.56 144.78) (xy 298.45 144.78)
		)
		(stroke
			(width 0)
			(type default)
		)
	)
	(wire
		(pts
			(xy 217.17 119.38) (xy 223.52 119.38)
		)
		(stroke
			(width 0)
			(type default)
		)
	)
	(wire
		(pts
			(xy 299.72 194.31) (xy 299.72 193.04)
		)
		(stroke
			(width 0)
			(type default)
		)
	)
	(wire
		(pts
			(xy 271.78 184.15) (xy 271.78 181.61)
		)
		(stroke
			(width 0)
			(type default)
		)
	)
	(wire
		(pts
			(xy 160.02 134.62) (xy 124.46 134.62)
		)
		(stroke
			(width 0)
			(type default)
		)
	)
	(wire
		(pts
			(xy 187.96 170.18) (xy 259.08 170.18)
		)
		(stroke
			(width 0)
			(type default)
		)
	)
	(wire
		(pts
			(xy 261.62 90.17) (xy 262.89 90.17)
		)
		(stroke
			(width 0)
			(type default)
		)
	)
	(wire
		(pts
			(xy 302.26 85.09) (xy 311.15 85.09)
		)
		(stroke
			(width 0)
			(type default)
		)
	)
	(wire
		(pts
			(xy 153.67 105.41) (xy 153.67 106.68)
		)
		(stroke
			(width 0)
			(type default)
		)
	)
	(wire
		(pts
			(xy 256.54 175.26) (xy 256.54 182.88)
		)
		(stroke
			(width 0)
			(type default)
		)
	)
	(wire
		(pts
			(xy 287.02 147.32) (xy 299.72 147.32)
		)
		(stroke
			(width 0)
			(type default)
		)
	)
	(wire
		(pts
			(xy 143.51 167.64) (xy 160.02 167.64)
		)
		(stroke
			(width 0)
			(type default)
		)
	)
	(wire
		(pts
			(xy 292.1 152.4) (xy 294.64 154.94)
		)
		(stroke
			(width 0)
			(type default)
		)
	)
	(wire
		(pts
			(xy 288.29 152.4) (xy 288.29 182.88)
		)
		(stroke
			(width 0)
			(type default)
		)
	)
	(wire
		(pts
			(xy 265.43 87.63) (xy 265.43 88.9)
		)
		(stroke
			(width 0)
			(type default)
		)
	)
	(wire
		(pts
			(xy 337.82 76.2) (xy 337.82 77.47)
		)
		(stroke
			(width 0)
			(type default)
		)
	)
	(wire
		(pts
			(xy 302.26 86.36) (xy 302.26 85.09)
		)
		(stroke
			(width 0)
			(type default)
		)
	)
	(wire
		(pts
			(xy 240.03 90.17) (xy 240.03 92.71)
		)
		(stroke
			(width 0)
			(type default)
		)
	)
	(wire
		(pts
			(xy 153.67 99.06) (xy 162.56 99.06)
		)
		(stroke
			(width 0)
			(type default)
		)
	)
	(wire
		(pts
			(xy 298.45 139.7) (xy 298.45 144.78)
		)
		(stroke
			(width 0)
			(type default)
		)
	)
	(wire
		(pts
			(xy 140.97 99.06) (xy 140.97 100.33)
		)
		(stroke
			(width 0)
			(type default)
		)
	)
	(polyline
		(pts
			(xy 83.82 132.08) (xy 132.08 132.08)
		)
		(stroke
			(width 0)
			(type default)
		)
	)
	(wire
		(pts
			(xy 82.55 180.34) (xy 82.55 181.61)
		)
		(stroke
			(width 0)
			(type default)
		)
	)
	(wire
		(pts
			(xy 187.96 121.92) (xy 209.55 121.92)
		)
		(stroke
			(width 0)
			(type default)
		)
	)
	(wire
		(pts
			(xy 217.17 114.3) (xy 217.17 119.38)
		)
		(stroke
			(width 0)
			(type default)
		)
	)
	(wire
		(pts
			(xy 218.44 90.17) (xy 226.06 90.17)
		)
		(stroke
			(width 0)
			(type default)
		)
	)
	(wire
		(pts
			(xy 298.45 85.09) (xy 298.45 127)
		)
		(stroke
			(width 0)
			(type default)
		)
	)
	(wire
		(pts
			(xy 237.49 78.74) (xy 237.49 81.28)
		)
		(stroke
			(width 0)
			(type default)
		)
	)
	(wire
		(pts
			(xy 187.96 134.62) (xy 284.48 134.62)
		)
		(stroke
			(width 0)
			(type default)
		)
	)
	(wire
		(pts
			(xy 222.25 162.56) (xy 280.67 162.56)
		)
		(stroke
			(width 0)
			(type default)
		)
	)
	(polyline
		(pts
			(xy 83.82 120.65) (xy 132.08 120.65)
		)
		(stroke
			(width 0)
			(type default)
		)
	)
	(wire
		(pts
			(xy 110.49 160.02) (xy 129.54 160.02)
		)
		(stroke
			(width 0)
			(type default)
		)
	)
	(wire
		(pts
			(xy 302.26 91.44) (xy 302.26 92.71)
		)
		(stroke
			(width 0)
			(type default)
		)
	)
	(wire
		(pts
			(xy 217.17 114.3) (xy 227.33 114.3)
		)
		(stroke
			(width 0)
			(type default)
		)
	)
	(wire
		(pts
			(xy 187.96 119.38) (xy 217.17 119.38)
		)
		(stroke
			(width 0)
			(type default)
		)
	)
	(wire
		(pts
			(xy 134.62 160.02) (xy 160.02 160.02)
		)
		(stroke
			(width 0)
			(type default)
		)
	)
	(wire
		(pts
			(xy 262.89 90.17) (xy 262.89 95.25)
		)
		(stroke
			(width 0)
			(type default)
		)
	)
	(wire
		(pts
			(xy 254 177.8) (xy 254 182.88)
		)
		(stroke
			(width 0)
			(type default)
		)
	)
	(wire
		(pts
			(xy 289.56 91.44) (xy 289.56 92.71)
		)
		(stroke
			(width 0)
			(type default)
		)
	)
	(bus
		(pts
			(xy 267.97 143.51) (xy 267.97 146.05)
		)
		(stroke
			(width 0)
			(type default)
		)
	)
	(wire
		(pts
			(xy 299.72 193.04) (xy 300.99 193.04)
		)
		(stroke
			(width 0)
			(type default)
		)
	)
	(wire
		(pts
			(xy 299.72 147.32) (xy 300.99 147.32)
		)
		(stroke
			(width 0)
			(type default)
		)
	)
	(wire
		(pts
			(xy 119.38 186.69) (xy 113.03 186.69)
		)
		(stroke
			(width 0)
			(type default)
		)
	)
	(wire
		(pts
			(xy 218.44 175.26) (xy 256.54 175.26)
		)
		(stroke
			(width 0)
			(type default)
		)
	)
	(wire
		(pts
			(xy 162.56 99.06) (xy 162.56 100.33)
		)
		(stroke
			(width 0)
			(type default)
		)
	)
	(wire
		(pts
			(xy 281.94 132.08) (xy 300.99 132.08)
		)
		(stroke
			(width 0)
			(type default)
		)
	)
	(wire
		(pts
			(xy 292.1 154.94) (xy 294.64 152.4)
		)
		(stroke
			(width 0)
			(type default)
		)
	)
	(wire
		(pts
			(xy 199.39 90.17) (xy 205.74 90.17)
		)
		(stroke
			(width 0)
			(type default)
		)
	)
	(wire
		(pts
			(xy 187.96 177.8) (xy 217.17 177.8)
		)
		(stroke
			(width 0)
			(type default)
		)
	)
	(wire
		(pts
			(xy 278.13 181.61) (xy 278.13 182.88)
		)
		(stroke
			(width 0)
			(type default)
		)
	)
	(wire
		(pts
			(xy 311.15 82.55) (xy 311.15 85.09)
		)
		(stroke
			(width 0)
			(type default)
		)
	)
	(wire
		(pts
			(xy 283.21 160.02) (xy 283.21 182.88)
		)
		(stroke
			(width 0)
			(type default)
		)
	)
	(wire
		(pts
			(xy 261.62 167.64) (xy 261.62 182.88)
		)
		(stroke
			(width 0)
			(type default)
		)
	)
	(wire
		(pts
			(xy 82.55 181.61) (xy 101.6 181.61)
		)
		(stroke
			(width 0)
			(type default)
		)
	)
	(wire
		(pts
			(xy 299.72 193.04) (xy 299.72 190.5)
		)
		(stroke
			(width 0)
			(type default)
		)
	)
	(bus
		(pts
			(xy 264.16 142.24) (xy 266.7 142.24)
		)
		(stroke
			(width 0)
			(type default)
		)
	)
	(wire
		(pts
			(xy 261.62 167.64) (xy 300.99 167.64)
		)
		(stroke
			(width 0)
			(type default)
		)
	)
	(wire
		(pts
			(xy 279.4 91.44) (xy 279.4 92.71)
		)
		(stroke
			(width 0)
			(type default)
		)
	)
	(wire
		(pts
			(xy 285.75 154.94) (xy 285.75 182.88)
		)
		(stroke
			(width 0)
			(type default)
		)
	)
	(wire
		(pts
			(xy 245.11 85.09) (xy 246.38 85.09)
		)
		(stroke
			(width 0)
			(type default)
		)
	)
	(wire
		(pts
			(xy 298.45 144.78) (xy 300.99 144.78)
		)
		(stroke
			(width 0)
			(type default)
		)
	)
	(label "USBC2_ADDR"
		(at 143.51 167.64 0)
		(effects
			(font
				(size 1.27 1.27)
			)
			(justify left bottom)
		)
	)
	(label "USBC2_RX2_N"
		(at 189.23 167.64 0)
		(effects
			(font
				(size 1.27 1.27)
			)
			(justify left bottom)
		)
	)
	(label "USBC2_TX1_N"
		(at 189.23 160.02 0)
		(effects
			(font
				(size 1.27 1.27)
			)
			(justify left bottom)
		)
	)
	(label "~{USBC2_EN_MUX}"
		(at 143.51 137.16 0)
		(effects
			(font
				(size 1.27 1.27)
			)
			(justify left bottom)
		)
	)
	(label "USBC2_VBUS_DET_MUX"
		(at 189.23 127 0)
		(effects
			(font
				(size 1.27 1.27)
			)
			(justify left bottom)
		)
	)
	(label "USBC2_TX2_N"
		(at 189.23 175.26 0)
		(effects
			(font
				(size 1.27 1.27)
			)
			(justify left bottom)
		)
	)
	(label "USBC2_CONN_TX2_P"
		(at 227.33 177.8 0)
		(effects
			(font
				(size 1.27 1.27)
			)
			(justify left bottom)
		)
	)
	(label "USBSS_TX_P"
		(at 143.51 162.56 0)
		(effects
			(font
				(size 1.27 1.27)
			)
			(justify left bottom)
		)
	)
	(label "USBC2_I2C_SDA"
		(at 143.51 170.18 0)
		(effects
			(font
				(size 1.27 1.27)
			)
			(justify left bottom)
		)
	)
	(label "I2C_{SYS}.SDA"
		(at 115.57 170.18 0)
		(effects
			(font
				(size 1.27 1.27)
			)
			(justify left bottom)
		)
	)
	(label "I2C_{SYS}.SCL"
		(at 115.57 172.72 0)
		(effects
			(font
				(size 1.27 1.27)
			)
			(justify left bottom)
		)
	)
	(label "USBC2_CC2"
		(at 233.68 134.62 0)
		(effects
			(font
				(size 1.27 1.27)
			)
			(justify left bottom)
		)
	)
	(label "USBC2_I2C_SCL"
		(at 144.78 189.23 180)
		(effects
			(font
				(size 1.27 1.27)
			)
			(justify right bottom)
		)
	)
	(label "~{USBC2_INT_R}"
		(at 143.51 175.26 0)
		(effects
			(font
				(size 1.27 1.27)
			)
			(justify left bottom)
		)
	)
	(label "USBSS0.TX-"
		(at 111.76 162.56 0)
		(effects
			(font
				(size 1.27 1.27)
			)
			(justify left bottom)
		)
	)
	(label "USBC2_ADDR"
		(at 101.6 181.61 180)
		(effects
			(font
				(size 1.27 1.27)
			)
			(justify right bottom)
		)
	)
	(label "USBSS_RX_P"
		(at 143.51 154.94 0)
		(effects
			(font
				(size 1.27 1.27)
			)
			(justify left bottom)
		)
	)
	(label "USBC2_I2C_SDA"
		(at 144.78 186.69 180)
		(effects
			(font
				(size 1.27 1.27)
			)
			(justify right bottom)
		)
	)
	(label "USBC2_DIR"
		(at 189.23 116.84 0)
		(effects
			(font
				(size 1.27 1.27)
			)
			(justify left bottom)
		)
	)
	(label "USBC2_I2C_SCL"
		(at 143.51 172.72 0)
		(effects
			(font
				(size 1.27 1.27)
			)
			(justify left bottom)
		)
	)
	(label "USBSS_TX_N"
		(at 143.51 160.02 0)
		(effects
			(font
				(size 1.27 1.27)
			)
			(justify left bottom)
		)
	)
	(label "USB0.D-"
		(at 270.51 147.32 0)
		(effects
			(font
				(size 1.27 1.27)
			)
			(justify left bottom)
		)
	)
	(label "USBC2_CONN_TX1_N"
		(at 227.33 160.02 0)
		(effects
			(font
				(size 1.27 1.27)
			)
			(justify left bottom)
		)
	)
	(label "USBC2_I_MODE"
		(at 143.51 132.08 0)
		(effects
			(font
				(size 1.27 1.27)
			)
			(justify left bottom)
		)
	)
	(label "USBC2_PORT"
		(at 143.51 134.62 0)
		(effects
			(font
				(size 1.27 1.27)
			)
			(justify left bottom)
		)
	)
	(label "USBC2_RX2_P"
		(at 189.23 170.18 0)
		(effects
			(font
				(size 1.27 1.27)
			)
			(justify left bottom)
		)
	)
	(label "USBC2_RX1_P"
		(at 189.23 154.94 0)
		(effects
			(font
				(size 1.27 1.27)
			)
			(justify left bottom)
		)
	)
	(label "USBC2_CONN_TX2_N"
		(at 227.33 175.26 0)
		(effects
			(font
				(size 1.27 1.27)
			)
			(justify left bottom)
		)
	)
	(label "USBSS0.TX+"
		(at 111.76 160.02 0)
		(effects
			(font
				(size 1.27 1.27)
			)
			(justify left bottom)
		)
	)
	(label "USBSS0.RX+"
		(at 111.76 152.4 0)
		(effects
			(font
				(size 1.27 1.27)
			)
			(justify left bottom)
		)
	)
	(label "USBC2_VBUS"
		(at 262.89 85.09 0)
		(effects
			(font
				(size 1.27 1.27)
			)
			(justify left bottom)
		)
	)
	(label "USBC2_CC1"
		(at 233.68 132.08 0)
		(effects
			(font
				(size 1.27 1.27)
			)
			(justify left bottom)
		)
	)
	(label "~{USBC2_EN_CC}"
		(at 143.51 139.7 0)
		(effects
			(font
				(size 1.27 1.27)
			)
			(justify left bottom)
		)
	)
	(label "USBC2_CONN_TX1_P"
		(at 227.33 162.56 0)
		(effects
			(font
				(size 1.27 1.27)
			)
			(justify left bottom)
		)
	)
	(label "USBC2_RX1_N"
		(at 189.23 152.4 0)
		(effects
			(font
				(size 1.27 1.27)
			)
			(justify left bottom)
		)
	)
	(label "USBC2_TX1_P"
		(at 189.23 162.56 0)
		(effects
			(font
				(size 1.27 1.27)
			)
			(justify left bottom)
		)
	)
	(label "USB0.D+"
		(at 270.51 144.78 0)
		(effects
			(font
				(size 1.27 1.27)
			)
			(justify left bottom)
		)
	)
	(label "USBC2_ID"
		(at 189.23 119.38 0)
		(effects
			(font
				(size 1.27 1.27)
			)
			(justify left bottom)
		)
	)
	(label "USBC2_TX2_P"
		(at 189.23 177.8 0)
		(effects
			(font
				(size 1.27 1.27)
			)
			(justify left bottom)
		)
	)
	(label "USBC2_FAULT_N"
		(at 189.23 121.92 0)
		(effects
			(font
				(size 1.27 1.27)
			)
			(justify left bottom)
		)
	)
	(label "USBSS0.RX-"
		(at 111.76 154.94 0)
		(effects
			(font
				(size 1.27 1.27)
			)
			(justify left bottom)
		)
	)
	(label "USBC2_ISET"
		(at 262.89 87.63 0)
		(effects
			(font
				(size 1.27 1.27)
			)
			(justify left bottom)
		)
	)
	(label "USBSS_RX_N"
		(at 143.51 152.4 0)
		(effects
			(font
				(size 1.27 1.27)
			)
			(justify left bottom)
		)
	)
	(hierarchical_label "I2C_{SYS}{I2C}"
		(shape bidirectional)
		(at 109.22 167.64 180)
		(effects
			(font
				(size 1.27 1.27)
			)
			(justify right)
		)
	)
	(hierarchical_label "USBSS0{USBSS}"
		(shape bidirectional)
		(at 105.41 149.86 180)
		(effects
			(font
				(size 1.27 1.27)
			)
			(justify right)
		)
	)
	(hierarchical_label "USBC2_PEN"
		(shape input)
		(at 199.39 90.17 180)
		(effects
			(font
				(size 1.27 1.27)
			)
			(justify right)
		)
	)
	(hierarchical_label "USB0{USB}"
		(shape input)
		(at 264.16 142.24 180)
		(effects
			(font
				(size 1.27 1.27)
			)
			(justify right)
		)
	)
	(hierarchical_label "~{USBC2_INT}"
		(shape output)
		(at 127 175.26 180)
		(effects
			(font
				(size 1.27 1.27)
			)
			(justify right)
		)
	)
	(hierarchical_label "USBC2_ID"
		(shape output)
		(at 234.95 114.3 0)
		(effects
			(font
				(size 1.27 1.27)
			)
			(justify left)
		)
	)
	(hierarchical_label "USBC2_VBUS_DET"
		(shape output)
		(at 342.9 76.2 0)
		(effects
			(font
				(size 1.27 1.27)
			)
			(justify left)
		)
	)
	(rule_area
		(polyline
			(pts
				(xy 158.75 165.1) (xy 110.49 165.1) (xy 110.49 149.86) (xy 158.75 149.86)
			)
			(stroke
				(width 0)
				(type dash)
			)
			(fill
				(type none)
			)
		)
	)
	(rule_area
		(polyline
			(pts
				(xy 248.92 180.975) (xy 189.3887 180.975) (xy 189.23 149.86) (xy 248.92 149.86)
			)
			(stroke
				(width 0)
				(type dash)
			)
			(fill
				(type none)
			)
		)
	)
	(rule_area
		(polyline
			(pts
				(xy 281.305 147.955) (xy 269.24 147.955) (xy 269.24 142.24) (xy 281.305 142.24)
			)
			(stroke
				(width 0)
				(type dash)
			)
			(fill
				(type none)
			)
		)
	)
	(netclass_flag ""
		(length 2.54)
		(shape round)
		(at 189.23 149.86 0)
		(effects
			(font
				(size 1.27 1.27)
			)
			(justify left bottom)
		)
		(property "Netclass" "85Ohm-diff_USB_SS"
			(at 190.246 147.32 0)
			(effects
				(font
					(size 1.27 1.27)
				)
				(justify left)
			)
		)
		(property "Component Class" ""
			(at 26.67 107.95 0)
			(effects
				(font
					(size 1.27 1.27)
					(italic yes)
				)
				(justify right)
			)
		)
	)
	(netclass_flag ""
		(length 2.54)
		(shape round)
		(at 269.24 142.24 0)
		(effects
			(font
				(size 1.27 1.27)
			)
			(justify left bottom)
		)
		(property "Netclass" "90Ohm-diff_USB_2.0"
			(at 267.716 139.7 0)
			(effects
				(font
					(size 1.27 1.27)
				)
				(justify right)
			)
		)
		(property "Component Class" ""
			(at 106.68 100.33 0)
			(effects
				(font
					(size 1.27 1.27)
					(italic yes)
				)
				(justify right)
			)
		)
	)
	(netclass_flag ""
		(length 2.54)
		(shape round)
		(at 110.49 149.86 0)
		(effects
			(font
				(size 1.27 1.27)
			)
			(justify left bottom)
		)
		(property "Netclass" "85Ohm-diff_USB_SS"
			(at 111.506 147.32 0)
			(effects
				(font
					(size 1.27 1.27)
				)
				(justify left)
			)
		)
		(property "Component Class" ""
			(at -52.07 107.95 0)
			(effects
				(font
					(size 1.27 1.27)
					(italic yes)
				)
				(justify right)
			)
		)
	)
	(symbol
		(lib_id "antmicroPMICPowerDistributionSwitchesLoadDrivers:AP22615A_TSOT26")
		(at 246.38 85.09 0)
		(unit 1)
		(exclude_from_sim no)
		(in_bom yes)
		(on_board yes)
		(dnp no)
		(property "Reference" "U23"
			(at 254 78.74 0)
			(effects
				(font
					(size 1.27 1.27)
				)
			)
		)
		(property "Value" "AP22615A_TSOT26"
			(at 276.86 90.17 0)
			(effects
				(font
					(size 1.27 1.27)
					(thickness 0.15)
				)
				(justify left bottom)
				(hide yes)
			)
		)
		(property "Footprint" "antmicro-footprints:TSOT23-6"
			(at 276.86 92.71 0)
			(effects
				(font
					(size 1.27 1.27)
					(thickness 0.15)
				)
				(justify left bottom)
				(hide yes)
			)
		)
		(property "Datasheet" "https://www.mouser.com/datasheet/2/115/DIOD_S_A0008958405_1-2543193.pdf"
			(at 276.86 95.25 0)
			(effects
				(font
					(size 1.27 1.27)
					(thickness 0.15)
				)
				(justify left bottom)
				(hide yes)
			)
		)
		(property "Description" "Power Load Distribution Switch, High Side, Active High, 1 Output, 5.5 V, 3.6 A, 0.04 ohm, TSOT-26-6"
			(at 246.38 85.09 0)
			(effects
				(font
					(size 1.27 1.27)
				)
				(hide yes)
			)
		)
		(property "MPN" "AP22615AWU-7"
			(at 254 81.28 0)
			(effects
				(font
					(size 1.27 1.27)
					(thickness 0.15)
				)
			)
		)
		(property "Manufacturer" "Diodes Incorporated"
			(at 276.86 100.33 0)
			(effects
				(font
					(size 1.27 1.27)
					(thickness 0.15)
				)
				(justify left bottom)
				(hide yes)
			)
		)
		(property "Author" "Antmicro"
			(at 276.86 102.87 0)
			(effects
				(font
					(size 1.27 1.27)
					(thickness 0.15)
				)
				(justify left bottom)
				(hide yes)
			)
		)
		(property "License" "Apache-2.0"
			(at 276.86 105.41 0)
			(effects
				(font
					(size 1.27 1.27)
					(thickness 0.15)
				)
				(justify left bottom)
				(hide yes)
			)
		)
		(pin "1"
		)
		(pin "2"
		)
		(pin "3"
		)
		(pin "4"
		)
		(pin "5"
		)
		(pin "6"
		)
		(instances
			(project "jetson-agx-thor-baseboard"
				(path ""
					(reference "U23")
					(unit 1)
				)
			)
		)
	)
	(symbol
		(lib_id "antmicropower:GND")
		(at 124.46 140.97 0)
		(unit 1)
		(exclude_from_sim no)
		(in_bom yes)
		(on_board yes)
		(dnp no)
		(property "Reference" "#PWR0458"
			(at 124.46 147.32 0)
			(effects
				(font
					(size 1.27 1.27)
				)
				(justify left bottom)
				(hide yes)
			)
		)
		(property "Value" "GND"
			(at 124.206 145.288 0)
			(effects
				(font
					(size 1.27 1.27)
					(thickness 0.15)
				)
			)
		)
		(property "Footprint" ""
			(at 133.35 148.59 0)
			(effects
				(font
					(size 1.27 1.27)
					(thickness 0.15)
				)
				(justify left bottom)
				(hide yes)
			)
		)
		(property "Datasheet" ""
			(at 133.35 153.67 0)
			(effects
				(font
					(size 1.27 1.27)
					(thickness 0.15)
				)
				(justify left bottom)
				(hide yes)
			)
		)
		(property "Description" ""
			(at 124.46 140.97 0)
			(effects
				(font
					(size 1.27 1.27)
				)
				(hide yes)
			)
		)
		(property "Author" "Antmicro"
			(at 133.35 148.59 0)
			(effects
				(font
					(size 1.27 1.27)
					(thickness 0.15)
				)
				(justify left bottom)
				(hide yes)
			)
		)
		(property "License" "Apache-2.0"
			(at 133.35 151.13 0)
			(effects
				(font
					(size 1.27 1.27)
					(thickness 0.15)
				)
				(justify left bottom)
				(hide yes)
			)
		)
		(pin "1"
		)
		(instances
			(project "jetson-agx-thor-baseboard"
				(path ""
					(reference "#PWR0458")
					(unit 1)
				)
			)
		)
	)
	(symbol
		(lib_id "antmicroTransistorsFETsMOSFETsSingle:DMG1012T-7")
		(at 233.68 100.33 0)
		(unit 1)
		(exclude_from_sim no)
		(in_bom yes)
		(on_board yes)
		(dnp no)
		(fields_autoplaced yes)
		(property "Reference" "Q19"
			(at 243.84 96.52 0)
			(effects
				(font
					(size 1.27 1.27)
					(thickness 0.15)
				)
				(justify left)
			)
		)
		(property "Value" "DMG1012T-7"
			(at 256.54 109.22 0)
			(effects
				(font
					(size 1.27 1.27)
					(thickness 0.15)
				)
				(justify left bottom)
				(hide yes)
			)
		)
		(property "Footprint" "antmicro-footprints:SOT-523"
			(at 256.54 111.76 0)
			(effects
				(font
					(size 1.27 1.27)
					(thickness 0.15)
				)
				(justify left bottom)
				(hide yes)
			)
		)
		(property "Datasheet" "https://www.diodes.com/assets/Datasheets/ds31783.pdf"
			(at 256.54 114.3 0)
			(effects
				(font
					(size 1.27 1.27)
					(thickness 0.15)
				)
				(justify left bottom)
				(hide yes)
			)
		)
		(property "Description" "Power MOSFET, N Channel, 20 V, 630 mA, 0.3 ohm, SOT-523, Surface Mount"
			(at 256.54 127 0)
			(effects
				(font
					(size 1.27 1.27)
				)
				(justify left bottom)
				(hide yes)
			)
		)
		(property "MPN" "DMG1012T-7"
			(at 243.84 99.06 0)
			(effects
				(font
					(size 1.27 1.27)
					(thickness 0.15)
				)
				(justify left)
			)
		)
		(property "Manufacturer" "Diodes Incorporated"
			(at 256.54 119.38 0)
			(effects
				(font
					(size 1.27 1.27)
					(thickness 0.15)
				)
				(justify left bottom)
				(hide yes)
			)
		)
		(property "Author" "Antmicro"
			(at 256.54 121.92 0)
			(effects
				(font
					(size 1.27 1.27)
					(thickness 0.15)
				)
				(justify left bottom)
				(hide yes)
			)
		)
		(property "License" "Apache-2.0"
			(at 256.54 124.46 0)
			(effects
				(font
					(size 1.27 1.27)
					(thickness 0.15)
				)
				(justify left bottom)
				(hide yes)
			)
		)
		(pin "3"
		)
		(pin "1"
		)
		(pin "2"
		)
		(instances
			(project "jetson-agx-thor-baseboard"
				(path ""
					(reference "Q19")
					(unit 1)
				)
			)
		)
	)
	(symbol
		(lib_id "antmicroResistors0402:R_200k_0402")
		(at 200.66 111.76 90)
		(unit 1)
		(exclude_from_sim no)
		(in_bom yes)
		(on_board yes)
		(dnp no)
		(property "Reference" "R255"
			(at 201.93 107.95 90)
			(effects
				(font
					(size 1.27 1.27)
				)
				(justify right)
			)
		)
		(property "Value" "R_200k_0402"
			(at 213.36 91.44 0)
			(effects
				(font
					(size 1.27 1.27)
					(thickness 0.15)
				)
				(justify left bottom)
				(hide yes)
			)
		)
		(property "Footprint" "antmicro-footprints:R_0402_1005Metric"
			(at 215.9 91.44 0)
			(effects
				(font
					(size 1.27 1.27)
					(thickness 0.15)
				)
				(justify left bottom)
				(hide yes)
			)
		)
		(property "Datasheet" "https://www.bourns.com/docs/product-datasheets/cr.pdf"
			(at 218.44 91.44 0)
			(effects
				(font
					(size 1.27 1.27)
					(thickness 0.15)
				)
				(justify left bottom)
				(hide yes)
			)
		)
		(property "Description" "SMD Chip Resistor, 200 kohm, ± 1%, 62.5 mW, 0402 [1005 Metric], Thick Film, General Purpose"
			(at 200.66 111.76 0)
			(effects
				(font
					(size 1.27 1.27)
				)
				(hide yes)
			)
		)
		(property "Manufacturer" "Bourns"
			(at 223.52 91.44 0)
			(effects
				(font
					(size 1.27 1.27)
					(thickness 0.15)
				)
				(justify left bottom)
				(hide yes)
			)
		)
		(property "MPN" "CR0402-FX-2003GLF"
			(at 220.98 91.44 0)
			(effects
				(font
					(size 1.27 1.27)
					(thickness 0.15)
				)
				(justify left bottom)
				(hide yes)
			)
		)
		(property "Val" "200k"
			(at 201.93 110.49 90)
			(effects
				(font
					(size 1.27 1.27)
					(thickness 0.15)
				)
				(justify right)
			)
		)
		(property "License" "Apache-2.0"
			(at 226.06 91.44 0)
			(effects
				(font
					(size 1.27 1.27)
					(thickness 0.15)
				)
				(justify left bottom)
				(hide yes)
			)
		)
		(property "Author" "Antmicro"
			(at 228.6 91.44 0)
			(effects
				(font
					(size 1.27 1.27)
					(thickness 0.15)
				)
				(justify left bottom)
				(hide yes)
			)
		)
		(property "Tolerance" "1%"
			(at 210.82 91.44 0)
			(effects
				(font
					(size 1.27 1.27)
				)
				(justify left bottom)
				(hide yes)
			)
		)
		(pin "1"
		)
		(pin "2"
		)
		(instances
			(project "jetson-agx-thor-baseboard"
				(path ""
					(reference "R255")
					(unit 1)
				)
			)
		)
	)
	(symbol
		(lib_id "antmicroResistors0402:R_0R_0402")
		(at 132.08 137.16 0)
		(unit 1)
		(exclude_from_sim no)
		(in_bom yes)
		(on_board yes)
		(dnp no)
		(property "Reference" "R276"
			(at 137.16 136.525 0)
			(effects
				(font
					(size 1.27 1.27)
				)
				(justify left bottom)
			)
		)
		(property "Value" "R_0R_0402"
			(at 152.4 149.86 0)
			(effects
				(font
					(size 1.27 1.27)
					(thickness 0.15)
				)
				(justify left bottom)
				(hide yes)
			)
		)
		(property "Footprint" "antmicro-footprints:R_0402_1005Metric"
			(at 152.4 152.4 0)
			(effects
				(font
					(size 1.27 1.27)
					(thickness 0.15)
				)
				(justify left bottom)
				(hide yes)
			)
		)
		(property "Datasheet" "https://industrial.panasonic.com/cdbs/www-data/pdf/RDA0000/AOA0000C301.pdf"
			(at 152.4 154.94 0)
			(effects
				(font
					(size 1.27 1.27)
					(thickness 0.15)
				)
				(justify left bottom)
				(hide yes)
			)
		)
		(property "Description" "SMD Chip Resistor, Jumper, 0 ohm, 100 mW, 0402 [1005 Metric], Thick Film, General Purpose"
			(at 132.08 137.16 0)
			(effects
				(font
					(size 1.27 1.27)
				)
				(hide yes)
			)
		)
		(property "Manufacturer" "Panasonic"
			(at 152.4 160.02 0)
			(effects
				(font
					(size 1.27 1.27)
					(thickness 0.15)
				)
				(justify left bottom)
				(hide yes)
			)
		)
		(property "MPN" "ERJ2GE0R00X"
			(at 152.4 157.48 0)
			(effects
				(font
					(size 1.27 1.27)
					(thickness 0.15)
				)
				(justify left bottom)
				(hide yes)
			)
		)
		(property "Val" "0R"
			(at 129.54 136.525 0)
			(effects
				(font
					(size 1.27 1.27)
					(thickness 0.15)
				)
				(justify left bottom)
			)
		)
		(property "License" "Apache-2.0"
			(at 152.4 162.56 0)
			(effects
				(font
					(size 1.27 1.27)
					(thickness 0.15)
				)
				(justify left bottom)
				(hide yes)
			)
		)
		(property "Author" "Antmicro"
			(at 152.4 165.1 0)
			(effects
				(font
					(size 1.27 1.27)
					(thickness 0.15)
				)
				(justify left bottom)
				(hide yes)
			)
		)
		(property "Tolerance" "~"
			(at 152.4 147.32 0)
			(effects
				(font
					(size 1.27 1.27)
				)
				(justify left bottom)
				(hide yes)
			)
		)
		(property "Current" "1A"
			(at 152.4 167.64 0)
			(effects
				(font
					(size 1.27 1.27)
					(thickness 0.15)
				)
				(justify left bottom)
				(hide yes)
			)
		)
		(pin "1"
		)
		(pin "2"
		)
		(instances
			(project "jetson-agx-thor-baseboard"
				(path ""
					(reference "R276")
					(unit 1)
				)
			)
		)
	)
	(symbol
		(lib_id "antmicroCapacitors0402:C_100n_0402")
		(at 218.44 175.26 180)
		(unit 1)
		(exclude_from_sim no)
		(in_bom yes)
		(on_board yes)
		(dnp no)
		(property "Reference" "C108"
			(at 222.25 173.228 0)
			(effects
				(font
					(size 1.27 1.27)
				)
				(justify left bottom)
			)
		)
		(property "Value" "C_100n_0402"
			(at 198.12 165.1 0)
			(effects
				(font
					(size 1.27 1.27)
					(thickness 0.15)
				)
				(justify left bottom)
				(hide yes)
			)
		)
		(property "Footprint" "antmicro-footprints:C_0402_1005Metric"
			(at 198.12 162.56 0)
			(effects
				(font
					(size 1.27 1.27)
					(thickness 0.15)
				)
				(justify left bottom)
				(hide yes)
			)
		)
		(property "Datasheet" "https://www.murata.com/products/productdetail?partno=GRM155R61H104KE14%23"
			(at 198.12 160.02 0)
			(effects
				(font
					(size 1.27 1.27)
					(thickness 0.15)
				)
				(justify left bottom)
				(hide yes)
			)
		)
		(property "Description" "SMD Multilayer Ceramic Capacitor, 0.1 µF, 50 V, 0402 [1005 Metric], ± 10%, X5R, GRM Series"
			(at 218.44 175.26 0)
			(effects
				(font
					(size 1.27 1.27)
				)
				(hide yes)
			)
		)
		(property "Manufacturer" "Murata"
			(at 198.12 154.94 0)
			(effects
				(font
					(size 1.27 1.27)
					(thickness 0.15)
				)
				(justify left bottom)
				(hide yes)
			)
		)
		(property "MPN" "GRM155R61H104KE14D"
			(at 198.12 157.48 0)
			(effects
				(font
					(size 1.27 1.27)
					(thickness 0.15)
				)
				(justify left bottom)
				(hide yes)
			)
		)
		(property "Val" "100n"
			(at 214.63 175.895 0)
			(effects
				(font
					(size 1.27 1.27)
					(thickness 0.15)
				)
				(justify left bottom)
			)
		)
		(property "License" "Apache-2.0"
			(at 198.12 152.4 0)
			(effects
				(font
					(size 1.27 1.27)
					(thickness 0.15)
				)
				(justify left bottom)
				(hide yes)
			)
		)
		(property "Author" "Antmicro"
			(at 198.12 149.86 0)
			(effects
				(font
					(size 1.27 1.27)
					(thickness 0.15)
				)
				(justify left bottom)
				(hide yes)
			)
		)
		(property "Voltage" "50V"
			(at 198.12 147.32 0)
			(effects
				(font
					(size 1.27 1.27)
				)
				(justify left bottom)
				(hide yes)
			)
		)
		(property "Dielectric" "X5R"
			(at 198.12 144.78 0)
			(effects
				(font
					(size 1.27 1.27)
				)
				(justify left bottom)
				(hide yes)
			)
		)
		(pin "1"
		)
		(pin "2"
		)
		(instances
			(project "jetson-agx-thor-baseboard"
				(path ""
					(reference "C108")
					(unit 1)
				)
			)
		)
	)
	(symbol
		(lib_id "antmicroInterfaceControllers:HD3SS3220IRNHR")
		(at 160.02 116.84 0)
		(unit 1)
		(exclude_from_sim no)
		(in_bom yes)
		(on_board yes)
		(dnp no)
		(fields_autoplaced yes)
		(property "Reference" "U56"
			(at 173.99 109.22 0)
			(effects
				(font
					(size 1.27 1.27)
					(thickness 0.15)
				)
			)
		)
		(property "Value" "HD3SS3220IRNHR"
			(at 201.93 124.46 0)
			(effects
				(font
					(size 1.27 1.27)
					(thickness 0.15)
				)
				(justify left bottom)
				(hide yes)
			)
		)
		(property "Footprint" "antmicro-footprints:WQFN-30-1EP_4.6x2.6mm_P0.4mm"
			(at 201.93 127 0)
			(effects
				(font
					(size 1.27 1.27)
					(thickness 0.15)
				)
				(justify left bottom)
				(hide yes)
			)
		)
		(property "Datasheet" "https://www.ti.com/lit/ds/symlink/hd3ss3220.pdf?ts=1663000043694&ref_url=https%253A%252F%252Fwww.google.com%252F"
			(at 201.93 129.54 0)
			(effects
				(font
					(size 1.27 1.27)
					(thickness 0.15)
				)
				(justify left bottom)
				(hide yes)
			)
		)
		(property "Description" "USB Interface IC 10-Gbps USB 3.1 Type-C 2:1 mux with DRP Controller 30-WQFN -40°C to 85°C"
			(at 160.02 116.84 0)
			(effects
				(font
					(size 1.27 1.27)
				)
				(hide yes)
			)
		)
		(property "Manufacturer" "Texas Instruments"
			(at 201.93 132.08 0)
			(effects
				(font
					(size 1.27 1.27)
					(thickness 0.15)
				)
				(justify left bottom)
				(hide yes)
			)
		)
		(property "MPN" "HD3SS3220IRNHR"
			(at 173.99 111.76 0)
			(effects
				(font
					(size 1.27 1.27)
					(thickness 0.15)
				)
			)
		)
		(property "Author" "Antmicro"
			(at 201.93 137.16 0)
			(effects
				(font
					(size 1.27 1.27)
					(thickness 0.15)
				)
				(justify left bottom)
				(hide yes)
			)
		)
		(property "License" "Apache-2.0"
			(at 201.93 139.7 0)
			(effects
				(font
					(size 1.27 1.27)
					(thickness 0.15)
				)
				(justify left bottom)
				(hide yes)
			)
		)
		(pin "19"
		)
		(pin "3"
		)
		(pin "10"
		)
		(pin "24"
		)
		(pin "11"
		)
		(pin "26"
		)
		(pin "8"
		)
		(pin "25"
		)
		(pin "16"
		)
		(pin "22"
		)
		(pin "21"
		)
		(pin "2"
		)
		(pin "20"
		)
		(pin "12"
		)
		(pin "6"
		)
		(pin "23"
		)
		(pin "9"
		)
		(pin "28"
		)
		(pin "30"
		)
		(pin "17"
		)
		(pin "29"
		)
		(pin "4"
		)
		(pin "5"
		)
		(pin "13"
		)
		(pin "14"
		)
		(pin "18"
		)
		(pin "7"
		)
		(pin "27"
		)
		(pin "1"
		)
		(pin "31"
		)
		(pin "15"
		)
		(instances
			(project "jetson-agx-thor-baseboard"
				(path ""
					(reference "U56")
					(unit 1)
				)
			)
		)
	)
	(symbol
		(lib_id "antmicropower:+5V")
		(at 237.49 71.12 0)
		(unit 1)
		(exclude_from_sim no)
		(in_bom yes)
		(on_board yes)
		(dnp no)
		(property "Reference" "#PWR0464"
			(at 237.49 74.93 0)
			(effects
				(font
					(size 1.27 1.27)
				)
				(justify left bottom)
				(hide yes)
			)
		)
		(property "Value" "+5V"
			(at 235.585 67.945 0)
			(effects
				(font
					(size 1.27 1.27)
					(thickness 0.15)
				)
				(justify left bottom)
			)
		)
		(property "Footprint" ""
			(at 252.73 78.74 0)
			(effects
				(font
					(size 1.27 1.27)
					(thickness 0.15)
				)
				(justify left bottom)
				(hide yes)
			)
		)
		(property "Datasheet" ""
			(at 252.73 81.28 0)
			(effects
				(font
					(size 1.27 1.27)
					(thickness 0.15)
				)
				(justify left bottom)
				(hide yes)
			)
		)
		(property "Description" ""
			(at 237.49 71.12 0)
			(effects
				(font
					(size 1.27 1.27)
				)
				(hide yes)
			)
		)
		(property "Author" "Antmicro"
			(at 252.73 78.74 0)
			(effects
				(font
					(size 1.27 1.27)
					(thickness 0.15)
				)
				(justify left bottom)
				(hide yes)
			)
		)
		(property "License" "Apache-2.0"
			(at 252.73 81.28 0)
			(effects
				(font
					(size 1.27 1.27)
					(thickness 0.15)
				)
				(justify left bottom)
				(hide yes)
			)
		)
		(pin "1"
		)
		(instances
			(project "jetson-agx-thor-baseboard"
				(path ""
					(reference "#PWR0464")
					(unit 1)
				)
			)
		)
	)
	(symbol
		(lib_id "antmicropower:GND")
		(at 240.03 104.14 0)
		(unit 1)
		(exclude_from_sim no)
		(in_bom yes)
		(on_board yes)
		(dnp no)
		(property "Reference" "#PWR0471"
			(at 240.03 110.49 0)
			(effects
				(font
					(size 1.27 1.27)
				)
				(justify left bottom)
				(hide yes)
			)
		)
		(property "Value" "GND"
			(at 240.03 107.95 0)
			(effects
				(font
					(size 1.27 1.27)
					(thickness 0.15)
				)
			)
		)
		(property "Footprint" ""
			(at 248.92 111.76 0)
			(effects
				(font
					(size 1.27 1.27)
					(thickness 0.15)
				)
				(justify left bottom)
				(hide yes)
			)
		)
		(property "Datasheet" ""
			(at 248.92 116.84 0)
			(effects
				(font
					(size 1.27 1.27)
					(thickness 0.15)
				)
				(justify left bottom)
				(hide yes)
			)
		)
		(property "Description" ""
			(at 240.03 104.14 0)
			(effects
				(font
					(size 1.27 1.27)
				)
				(hide yes)
			)
		)
		(property "Author" "Antmicro"
			(at 248.92 111.76 0)
			(effects
				(font
					(size 1.27 1.27)
					(thickness 0.15)
				)
				(justify left bottom)
				(hide yes)
			)
		)
		(property "License" "Apache-2.0"
			(at 248.92 114.3 0)
			(effects
				(font
					(size 1.27 1.27)
					(thickness 0.15)
				)
				(justify left bottom)
				(hide yes)
			)
		)
		(pin "1"
		)
		(instances
			(project "jetson-agx-thor-baseboard"
				(path ""
					(reference "#PWR0471")
					(unit 1)
				)
			)
		)
	)
	(symbol
		(lib_id "antmicroTestPoints:TP_0.75mm_SMD")
		(at 223.52 119.38 0)
		(unit 1)
		(exclude_from_sim no)
		(in_bom no)
		(on_board yes)
		(dnp no)
		(property "Reference" "TP45"
			(at 227.33 119.38 0)
			(effects
				(font
					(size 1.27 1.27)
				)
				(justify left)
			)
		)
		(property "Value" "TP_0.75mm_SMD"
			(at 233.68 123.19 0)
			(effects
				(font
					(size 1.27 1.27)
					(thickness 0.15)
				)
				(justify left bottom)
				(hide yes)
			)
		)
		(property "Footprint" "antmicro-footprints:TP_SMD_0.75mm"
			(at 233.68 125.73 0)
			(effects
				(font
					(size 1.27 1.27)
					(thickness 0.15)
				)
				(justify left bottom)
				(hide yes)
			)
		)
		(property "Datasheet" ""
			(at 241.3 132.08 0)
			(effects
				(font
					(size 1.27 1.27)
					(thickness 0.15)
				)
				(justify left bottom)
				(hide yes)
			)
		)
		(property "Description" "SMT test point"
			(at 223.52 119.38 0)
			(effects
				(font
					(size 1.27 1.27)
				)
				(hide yes)
			)
		)
		(property "MPN" ""
			(at 234.315 130.81 0)
			(effects
				(font
					(size 1.27 1.27)
					(thickness 0.15)
				)
				(justify left bottom)
				(hide yes)
			)
		)
		(property "Manufacturer" ""
			(at 234.315 125.73 0)
			(effects
				(font
					(size 1.27 1.27)
					(thickness 0.15)
				)
				(justify left bottom)
				(hide yes)
			)
		)
		(property "Author" "Antmicro"
			(at 233.68 128.27 0)
			(effects
				(font
					(size 1.27 1.27)
					(thickness 0.15)
				)
				(justify left bottom)
				(hide yes)
			)
		)
		(property "License" "Apache-2.0"
			(at 233.68 130.81 0)
			(effects
				(font
					(size 1.27 1.27)
					(thickness 0.15)
				)
				(justify left bottom)
				(hide yes)
			)
		)
		(pin "1"
		)
		(instances
			(project "jetson-agx-thor-baseboard"
				(path ""
					(reference "TP45")
					(unit 1)
				)
			)
		)
	)
	(symbol
		(lib_id "antmicroResistors0402:R_0R_0402")
		(at 82.55 187.96 90)
		(unit 1)
		(exclude_from_sim no)
		(in_bom no)
		(on_board yes)
		(dnp yes)
		(property "Reference" "R253"
			(at 83.82 184.15 90)
			(effects
				(font
					(size 1.27 1.27)
				)
				(justify right)
			)
		)
		(property "Value" "R_0R_0402"
			(at 95.25 167.64 0)
			(effects
				(font
					(size 1.27 1.27)
					(thickness 0.15)
				)
				(justify left bottom)
				(hide yes)
			)
		)
		(property "Footprint" "antmicro-footprints:R_0402_1005Metric"
			(at 97.79 167.64 0)
			(effects
				(font
					(size 1.27 1.27)
					(thickness 0.15)
				)
				(justify left bottom)
				(hide yes)
			)
		)
		(property "Datasheet" "https://industrial.panasonic.com/cdbs/www-data/pdf/RDA0000/AOA0000C301.pdf"
			(at 100.33 167.64 0)
			(effects
				(font
					(size 1.27 1.27)
					(thickness 0.15)
				)
				(justify left bottom)
				(hide yes)
			)
		)
		(property "Description" "SMD Chip Resistor, Jumper, 0 ohm, 100 mW, 0402 [1005 Metric], Thick Film, General Purpose"
			(at 82.55 187.96 0)
			(effects
				(font
					(size 1.27 1.27)
				)
				(hide yes)
			)
		)
		(property "Manufacturer" "Panasonic"
			(at 105.41 167.64 0)
			(effects
				(font
					(size 1.27 1.27)
					(thickness 0.15)
				)
				(justify left bottom)
				(hide yes)
			)
		)
		(property "MPN" "ERJ2GE0R00X"
			(at 102.87 167.64 0)
			(effects
				(font
					(size 1.27 1.27)
					(thickness 0.15)
				)
				(justify left bottom)
				(hide yes)
			)
		)
		(property "Val" "0R"
			(at 83.82 186.69 90)
			(effects
				(font
					(size 1.27 1.27)
					(thickness 0.15)
				)
				(justify right)
			)
		)
		(property "License" "Apache-2.0"
			(at 107.95 167.64 0)
			(effects
				(font
					(size 1.27 1.27)
					(thickness 0.15)
				)
				(justify left bottom)
				(hide yes)
			)
		)
		(property "Author" "Antmicro"
			(at 110.49 167.64 0)
			(effects
				(font
					(size 1.27 1.27)
					(thickness 0.15)
				)
				(justify left bottom)
				(hide yes)
			)
		)
		(property "Tolerance" "~"
			(at 92.71 167.64 0)
			(effects
				(font
					(size 1.27 1.27)
				)
				(justify left bottom)
				(hide yes)
			)
		)
		(property "Current" "1A"
			(at 113.03 167.64 0)
			(effects
				(font
					(size 1.27 1.27)
					(thickness 0.15)
				)
				(justify left bottom)
				(hide yes)
			)
		)
		(pin "1"
		)
		(pin "2"
		)
		(instances
			(project "jetson-agx-thor-baseboard"
				(path ""
					(reference "R253")
					(unit 1)
				)
			)
		)
	)
	(symbol
		(lib_id "antmicropower:+3V3")
		(at 200.66 105.41 0)
		(mirror y)
		(unit 1)
		(exclude_from_sim no)
		(in_bom yes)
		(on_board yes)
		(dnp no)
		(property "Reference" "#PWR0461"
			(at 200.66 109.22 0)
			(effects
				(font
					(size 1.27 1.27)
				)
				(justify left bottom)
				(hide yes)
			)
		)
		(property "Value" "+3V3"
			(at 197.485 101.6 0)
			(effects
				(font
					(size 1.27 1.27)
					(thickness 0.15)
				)
				(justify right)
			)
		)
		(property "Footprint" ""
			(at 185.42 113.03 0)
			(effects
				(font
					(size 1.27 1.27)
					(thickness 0.15)
				)
				(justify left bottom)
				(hide yes)
			)
		)
		(property "Datasheet" ""
			(at 185.42 115.57 0)
			(effects
				(font
					(size 1.27 1.27)
					(thickness 0.15)
				)
				(justify left bottom)
				(hide yes)
			)
		)
		(property "Description" ""
			(at 200.66 105.41 0)
			(effects
				(font
					(size 1.27 1.27)
				)
				(hide yes)
			)
		)
		(property "Author" "Antmicro"
			(at 185.42 107.95 0)
			(effects
				(font
					(size 1.27 1.27)
					(thickness 0.15)
				)
				(justify left bottom)
				(hide yes)
			)
		)
		(property "License" "Apache-2.0"
			(at 185.42 110.49 0)
			(effects
				(font
					(size 1.27 1.27)
					(thickness 0.15)
				)
				(justify left bottom)
				(hide yes)
			)
		)
		(pin "1"
		)
		(instances
			(project "jetson-agx-thor-baseboard"
				(path ""
					(reference "#PWR0461")
					(unit 1)
				)
			)
		)
	)
	(symbol
		(lib_id "antmicroCapacitors0402:C_100n_0402")
		(at 132.08 162.56 0)
		(mirror x)
		(unit 1)
		(exclude_from_sim no)
		(in_bom yes)
		(on_board yes)
		(dnp no)
		(property "Reference" "C252"
			(at 138.43 161.29 0)
			(effects
				(font
					(size 1.27 1.27)
				)
			)
		)
		(property "Value" "C_100n_0402"
			(at 152.4 152.4 0)
			(effects
				(font
					(size 1.27 1.27)
					(thickness 0.15)
				)
				(justify left bottom)
				(hide yes)
			)
		)
		(property "Footprint" "antmicro-footprints:C_0402_1005Metric"
			(at 152.4 149.86 0)
			(effects
				(font
					(size 1.27 1.27)
					(thickness 0.15)
				)
				(justify left bottom)
				(hide yes)
			)
		)
		(property "Datasheet" "https://www.murata.com/products/productdetail?partno=GRM155R61H104KE14%23"
			(at 152.4 147.32 0)
			(effects
				(font
					(size 1.27 1.27)
					(thickness 0.15)
				)
				(justify left bottom)
				(hide yes)
			)
		)
		(property "Description" "SMD Multilayer Ceramic Capacitor, 0.1 µF, 50 V, 0402 [1005 Metric], ± 10%, X5R, GRM Series"
			(at 132.08 162.56 0)
			(effects
				(font
					(size 1.27 1.27)
				)
				(hide yes)
			)
		)
		(property "Manufacturer" "Murata"
			(at 152.4 142.24 0)
			(effects
				(font
					(size 1.27 1.27)
					(thickness 0.15)
				)
				(justify left bottom)
				(hide yes)
			)
		)
		(property "MPN" "GRM155R61H104KE14D"
			(at 152.4 144.78 0)
			(effects
				(font
					(size 1.27 1.27)
					(thickness 0.15)
				)
				(justify left bottom)
				(hide yes)
			)
		)
		(property "Val" "100n"
			(at 130.81 163.83 0)
			(effects
				(font
					(size 1.27 1.27)
					(thickness 0.15)
				)
			)
		)
		(property "License" "Apache-2.0"
			(at 152.4 139.7 0)
			(effects
				(font
					(size 1.27 1.27)
					(thickness 0.15)
				)
				(justify left bottom)
				(hide yes)
			)
		)
		(property "Author" "Antmicro"
			(at 152.4 137.16 0)
			(effects
				(font
					(size 1.27 1.27)
					(thickness 0.15)
				)
				(justify left bottom)
				(hide yes)
			)
		)
		(property "Voltage" "50V"
			(at 152.4 134.62 0)
			(effects
				(font
					(size 1.27 1.27)
				)
				(justify left bottom)
				(hide yes)
			)
		)
		(property "Dielectric" "X5R"
			(at 152.4 132.08 0)
			(effects
				(font
					(size 1.27 1.27)
				)
				(justify left bottom)
				(hide yes)
			)
		)
		(pin "1"
		)
		(pin "2"
		)
		(instances
			(project "jetson-agx-thor-baseboard"
				(path ""
					(reference "C252")
					(unit 1)
				)
			)
		)
	)
	(symbol
		(lib_id "antmicroCapacitors0402:C_100n_0402")
		(at 222.25 177.8 180)
		(unit 1)
		(exclude_from_sim no)
		(in_bom yes)
		(on_board yes)
		(dnp no)
		(property "Reference" "C110"
			(at 226.06 175.768 0)
			(effects
				(font
					(size 1.27 1.27)
				)
				(justify left bottom)
			)
		)
		(property "Value" "C_100n_0402"
			(at 201.93 167.64 0)
			(effects
				(font
					(size 1.27 1.27)
					(thickness 0.15)
				)
				(justify left bottom)
				(hide yes)
			)
		)
		(property "Footprint" "antmicro-footprints:C_0402_1005Metric"
			(at 201.93 165.1 0)
			(effects
				(font
					(size 1.27 1.27)
					(thickness 0.15)
				)
				(justify left bottom)
				(hide yes)
			)
		)
		(property "Datasheet" "https://www.murata.com/products/productdetail?partno=GRM155R61H104KE14%23"
			(at 201.93 162.56 0)
			(effects
				(font
					(size 1.27 1.27)
					(thickness 0.15)
				)
				(justify left bottom)
				(hide yes)
			)
		)
		(property "Description" "SMD Multilayer Ceramic Capacitor, 0.1 µF, 50 V, 0402 [1005 Metric], ± 10%, X5R, GRM Series"
			(at 222.25 177.8 0)
			(effects
				(font
					(size 1.27 1.27)
				)
				(hide yes)
			)
		)
		(property "Manufacturer" "Murata"
			(at 201.93 157.48 0)
			(effects
				(font
					(size 1.27 1.27)
					(thickness 0.15)
				)
				(justify left bottom)
				(hide yes)
			)
		)
		(property "MPN" "GRM155R61H104KE14D"
			(at 201.93 160.02 0)
			(effects
				(font
					(size 1.27 1.27)
					(thickness 0.15)
				)
				(justify left bottom)
				(hide yes)
			)
		)
		(property "Val" "100n"
			(at 218.44 178.435 0)
			(effects
				(font
					(size 1.27 1.27)
					(thickness 0.15)
				)
				(justify left bottom)
			)
		)
		(property "License" "Apache-2.0"
			(at 201.93 154.94 0)
			(effects
				(font
					(size 1.27 1.27)
					(thickness 0.15)
				)
				(justify left bottom)
				(hide yes)
			)
		)
		(property "Author" "Antmicro"
			(at 201.93 152.4 0)
			(effects
				(font
					(size 1.27 1.27)
					(thickness 0.15)
				)
				(justify left bottom)
				(hide yes)
			)
		)
		(property "Voltage" "50V"
			(at 201.93 149.86 0)
			(effects
				(font
					(size 1.27 1.27)
				)
				(justify left bottom)
				(hide yes)
			)
		)
		(property "Dielectric" "X5R"
			(at 201.93 147.32 0)
			(effects
				(font
					(size 1.27 1.27)
				)
				(justify left bottom)
				(hide yes)
			)
		)
		(pin "1"
		)
		(pin "2"
		)
		(instances
			(project "jetson-agx-thor-baseboard"
				(path ""
					(reference "C110")
					(unit 1)
				)
			)
		)
	)
	(symbol
		(lib_id "antmicropower:GND")
		(at 265.43 96.52 0)
		(unit 1)
		(exclude_from_sim no)
		(in_bom yes)
		(on_board yes)
		(dnp no)
		(property "Reference" "#PWR0473"
			(at 265.43 102.87 0)
			(effects
				(font
					(size 1.27 1.27)
				)
				(justify left bottom)
				(hide yes)
			)
		)
		(property "Value" "GND"
			(at 265.43 100.33 0)
			(effects
				(font
					(size 1.27 1.27)
					(thickness 0.15)
				)
			)
		)
		(property "Footprint" ""
			(at 274.32 104.14 0)
			(effects
				(font
					(size 1.27 1.27)
					(thickness 0.15)
				)
				(justify left bottom)
				(hide yes)
			)
		)
		(property "Datasheet" ""
			(at 274.32 109.22 0)
			(effects
				(font
					(size 1.27 1.27)
					(thickness 0.15)
				)
				(justify left bottom)
				(hide yes)
			)
		)
		(property "Description" ""
			(at 265.43 96.52 0)
			(effects
				(font
					(size 1.27 1.27)
				)
				(hide yes)
			)
		)
		(property "Author" "Antmicro"
			(at 274.32 104.14 0)
			(effects
				(font
					(size 1.27 1.27)
					(thickness 0.15)
				)
				(justify left bottom)
				(hide yes)
			)
		)
		(property "License" "Apache-2.0"
			(at 274.32 106.68 0)
			(effects
				(font
					(size 1.27 1.27)
					(thickness 0.15)
				)
				(justify left bottom)
				(hide yes)
			)
		)
		(pin "1"
		)
		(instances
			(project "jetson-agx-thor-baseboard"
				(path ""
					(reference "#PWR0473")
					(unit 1)
				)
			)
		)
	)
	(symbol
		(lib_id "antmicropower:GND")
		(at 271.78 184.15 0)
		(unit 1)
		(exclude_from_sim no)
		(in_bom yes)
		(on_board yes)
		(dnp no)
		(property "Reference" "#PWR0474"
			(at 271.78 190.5 0)
			(effects
				(font
					(size 1.27 1.27)
				)
				(justify left bottom)
				(hide yes)
			)
		)
		(property "Value" "GND"
			(at 271.78 187.96 0)
			(effects
				(font
					(size 1.27 1.27)
					(thickness 0.15)
				)
			)
		)
		(property "Footprint" ""
			(at 280.67 191.77 0)
			(effects
				(font
					(size 1.27 1.27)
					(thickness 0.15)
				)
				(justify left bottom)
				(hide yes)
			)
		)
		(property "Datasheet" ""
			(at 280.67 196.85 0)
			(effects
				(font
					(size 1.27 1.27)
					(thickness 0.15)
				)
				(justify left bottom)
				(hide yes)
			)
		)
		(property "Description" ""
			(at 271.78 184.15 0)
			(effects
				(font
					(size 1.27 1.27)
				)
				(hide yes)
			)
		)
		(property "Author" "Antmicro"
			(at 280.67 191.77 0)
			(effects
				(font
					(size 1.27 1.27)
					(thickness 0.15)
				)
				(justify left bottom)
				(hide yes)
			)
		)
		(property "License" "Apache-2.0"
			(at 280.67 194.31 0)
			(effects
				(font
					(size 1.27 1.27)
					(thickness 0.15)
				)
				(justify left bottom)
				(hide yes)
			)
		)
		(pin "1"
		)
		(instances
			(project "jetson-agx-thor-baseboard"
				(path ""
					(reference "#PWR0474")
					(unit 1)
				)
			)
		)
	)
	(symbol
		(lib_id "antmicroResistors0402:R_1k_0402")
		(at 218.44 87.63 90)
		(unit 1)
		(exclude_from_sim no)
		(in_bom yes)
		(on_board yes)
		(dnp no)
		(property "Reference" "R265"
			(at 219.71 83.82 90)
			(effects
				(font
					(size 1.27 1.27)
				)
				(justify right)
			)
		)
		(property "Value" "R_1k_0402"
			(at 231.14 67.31 0)
			(effects
				(font
					(size 1.27 1.27)
					(thickness 0.15)
				)
				(justify left bottom)
				(hide yes)
			)
		)
		(property "Footprint" "antmicro-footprints:R_0402_1005Metric"
			(at 233.68 67.31 0)
			(effects
				(font
					(size 1.27 1.27)
					(thickness 0.15)
				)
				(justify left bottom)
				(hide yes)
			)
		)
		(property "Datasheet" "https://www.bourns.com/docs/product-datasheets/cr.pdf"
			(at 236.22 67.31 0)
			(effects
				(font
					(size 1.27 1.27)
					(thickness 0.15)
				)
				(justify left bottom)
				(hide yes)
			)
		)
		(property "Description" "SMD Chip Resistor, 1 kohm, ± 1%, 63 mW, 0402 [1005 Metric], Thick Film, General Purpose"
			(at 218.44 87.63 0)
			(effects
				(font
					(size 1.27 1.27)
				)
				(hide yes)
			)
		)
		(property "Manufacturer" "Bourns"
			(at 241.3 67.31 0)
			(effects
				(font
					(size 1.27 1.27)
					(thickness 0.15)
				)
				(justify left bottom)
				(hide yes)
			)
		)
		(property "MPN" "CR0402-FX-1001GLF"
			(at 238.76 67.31 0)
			(effects
				(font
					(size 1.27 1.27)
					(thickness 0.15)
				)
				(justify left bottom)
				(hide yes)
			)
		)
		(property "Val" "1k"
			(at 219.71 86.36 90)
			(effects
				(font
					(size 1.27 1.27)
					(thickness 0.15)
				)
				(justify right)
			)
		)
		(property "License" "Apache-2.0"
			(at 243.84 67.31 0)
			(effects
				(font
					(size 1.27 1.27)
					(thickness 0.15)
				)
				(justify left bottom)
				(hide yes)
			)
		)
		(property "Author" "Antmicro"
			(at 246.38 67.31 0)
			(effects
				(font
					(size 1.27 1.27)
					(thickness 0.15)
				)
				(justify left bottom)
				(hide yes)
			)
		)
		(property "Tolerance" "1%"
			(at 228.6 67.31 0)
			(effects
				(font
					(size 1.27 1.27)
				)
				(justify left bottom)
				(hide yes)
			)
		)
		(pin "1"
		)
		(pin "2"
		)
		(instances
			(project "jetson-agx-thor-baseboard"
				(path ""
					(reference "R265")
					(unit 1)
				)
			)
		)
	)
	(symbol
		(lib_id "antmicroTVSDiodes:TPD4E05U06QDQARQ1")
		(at 261.62 182.88 270)
		(unit 1)
		(exclude_from_sim no)
		(in_bom yes)
		(on_board yes)
		(dnp no)
		(property "Reference" "U26"
			(at 257.175 193.04 90)
			(effects
				(font
					(size 1.27 1.27)
				)
			)
		)
		(property "Value" "TPD4E05U06QDQARQ1"
			(at 251.46 207.01 0)
			(effects
				(font
					(size 1.27 1.27)
					(thickness 0.15)
				)
				(justify left bottom)
				(hide yes)
			)
		)
		(property "Footprint" "antmicro-footprints:USON-10_2.5x1mm_P0.5mm"
			(at 256.54 207.01 0)
			(effects
				(font
					(size 1.27 1.27)
					(thickness 0.15)
				)
				(justify left bottom)
				(hide yes)
			)
		)
		(property "Datasheet" "https://www.ti.com/lit/ds/symlink/tpd4e05u06-q1.pdf?HQS=dis-mous-null-mousermode-dsf-pf-null-wwe&ts=1663591265741&ref_url=https%253A%252F%252Fwww.mouser.com%252F"
			(at 254 207.01 0)
			(effects
				(font
					(size 1.27 1.27)
					(thickness 0.15)
				)
				(justify left bottom)
				(hide yes)
			)
		)
		(property "Description" "TVS diode array, 12 kV, USON-10, 5.5 V, 0.5 pF"
			(at 261.62 182.88 0)
			(effects
				(font
					(size 1.27 1.27)
				)
				(hide yes)
			)
		)
		(property "Manufacturer" "Texas Instruments"
			(at 248.92 207.01 0)
			(effects
				(font
					(size 1.27 1.27)
					(thickness 0.15)
				)
				(justify left bottom)
				(hide yes)
			)
		)
		(property "MPN" "TPD4E05U06QDQARQ1"
			(at 257.175 195.58 90)
			(effects
				(font
					(size 1.27 1.27)
					(thickness 0.15)
				)
			)
		)
		(property "Author" "Antmicro"
			(at 246.38 207.01 0)
			(effects
				(font
					(size 1.27 1.27)
					(thickness 0.15)
				)
				(justify left bottom)
				(hide yes)
			)
		)
		(property "License" "Apache-2.0"
			(at 243.84 207.01 0)
			(effects
				(font
					(size 1.27 1.27)
					(thickness 0.15)
				)
				(justify left bottom)
				(hide yes)
			)
		)
		(pin "1"
		)
		(pin "10"
		)
		(pin "2"
		)
		(pin "3"
		)
		(pin "4"
		)
		(pin "5"
		)
		(pin "6"
		)
		(pin "7"
		)
		(pin "8"
		)
		(pin "9"
		)
		(instances
			(project "jetson-agx-thor-baseboard"
				(path ""
					(reference "U26")
					(unit 1)
				)
			)
		)
	)
	(symbol
		(lib_id "antmicroResistors0402:R_0R_0402")
		(at 82.55 180.34 90)
		(unit 1)
		(exclude_from_sim no)
		(in_bom no)
		(on_board yes)
		(dnp yes)
		(property "Reference" "R252"
			(at 83.82 176.53 90)
			(effects
				(font
					(size 1.27 1.27)
				)
				(justify right)
			)
		)
		(property "Value" "R_0R_0402"
			(at 95.25 160.02 0)
			(effects
				(font
					(size 1.27 1.27)
					(thickness 0.15)
				)
				(justify left bottom)
				(hide yes)
			)
		)
		(property "Footprint" "antmicro-footprints:R_0402_1005Metric"
			(at 97.79 160.02 0)
			(effects
				(font
					(size 1.27 1.27)
					(thickness 0.15)
				)
				(justify left bottom)
				(hide yes)
			)
		)
		(property "Datasheet" "https://industrial.panasonic.com/cdbs/www-data/pdf/RDA0000/AOA0000C301.pdf"
			(at 100.33 160.02 0)
			(effects
				(font
					(size 1.27 1.27)
					(thickness 0.15)
				)
				(justify left bottom)
				(hide yes)
			)
		)
		(property "Description" "SMD Chip Resistor, Jumper, 0 ohm, 100 mW, 0402 [1005 Metric], Thick Film, General Purpose"
			(at 82.55 180.34 0)
			(effects
				(font
					(size 1.27 1.27)
				)
				(hide yes)
			)
		)
		(property "Manufacturer" "Panasonic"
			(at 105.41 160.02 0)
			(effects
				(font
					(size 1.27 1.27)
					(thickness 0.15)
				)
				(justify left bottom)
				(hide yes)
			)
		)
		(property "MPN" "ERJ2GE0R00X"
			(at 102.87 160.02 0)
			(effects
				(font
					(size 1.27 1.27)
					(thickness 0.15)
				)
				(justify left bottom)
				(hide yes)
			)
		)
		(property "Val" "0R"
			(at 83.82 179.07 90)
			(effects
				(font
					(size 1.27 1.27)
					(thickness 0.15)
				)
				(justify right)
			)
		)
		(property "License" "Apache-2.0"
			(at 107.95 160.02 0)
			(effects
				(font
					(size 1.27 1.27)
					(thickness 0.15)
				)
				(justify left bottom)
				(hide yes)
			)
		)
		(property "Author" "Antmicro"
			(at 110.49 160.02 0)
			(effects
				(font
					(size 1.27 1.27)
					(thickness 0.15)
				)
				(justify left bottom)
				(hide yes)
			)
		)
		(property "Tolerance" "~"
			(at 92.71 160.02 0)
			(effects
				(font
					(size 1.27 1.27)
				)
				(justify left bottom)
				(hide yes)
			)
		)
		(property "Current" "1A"
			(at 113.03 160.02 0)
			(effects
				(font
					(size 1.27 1.27)
					(thickness 0.15)
				)
				(justify left bottom)
				(hide yes)
			)
		)
		(pin "1"
		)
		(pin "2"
		)
		(instances
			(project "jetson-agx-thor-baseboard"
				(path ""
					(reference "R252")
					(unit 1)
				)
			)
		)
	)
	(symbol
		(lib_id "antmicroResistors0402:R_470R_0402")
		(at 321.31 91.44 90)
		(unit 1)
		(exclude_from_sim no)
		(in_bom yes)
		(on_board yes)
		(dnp no)
		(property "Reference" "R271"
			(at 322.58 87.63 90)
			(effects
				(font
					(size 1.27 1.27)
				)
				(justify right)
			)
		)
		(property "Value" "R_470R_0402"
			(at 334.01 71.12 0)
			(effects
				(font
					(size 1.27 1.27)
					(thickness 0.15)
				)
				(justify left bottom)
				(hide yes)
			)
		)
		(property "Footprint" "antmicro-footprints:R_0402_1005Metric"
			(at 336.55 71.12 0)
			(effects
				(font
					(size 1.27 1.27)
					(thickness 0.15)
				)
				(justify left bottom)
				(hide yes)
			)
		)
		(property "Datasheet" "https://www.bourns.com/docs/product-datasheets/cr.pdf"
			(at 339.09 71.12 0)
			(effects
				(font
					(size 1.27 1.27)
					(thickness 0.15)
				)
				(justify left bottom)
				(hide yes)
			)
		)
		(property "Description" "SMD Chip Resistor, 470 ohm, ± 1%, 62.5 mW, 0402 [1005 Metric], Thick Film, General Purpose"
			(at 321.31 91.44 0)
			(effects
				(font
					(size 1.27 1.27)
				)
				(hide yes)
			)
		)
		(property "Manufacturer" "Bourns"
			(at 344.17 71.12 0)
			(effects
				(font
					(size 1.27 1.27)
					(thickness 0.15)
				)
				(justify left bottom)
				(hide yes)
			)
		)
		(property "MPN" "CR0402-FX-4700GLF"
			(at 341.63 71.12 0)
			(effects
				(font
					(size 1.27 1.27)
					(thickness 0.15)
				)
				(justify left bottom)
				(hide yes)
			)
		)
		(property "Val" "470R"
			(at 322.58 90.17 90)
			(effects
				(font
					(size 1.27 1.27)
					(thickness 0.15)
				)
				(justify right)
			)
		)
		(property "License" "Apache-2.0"
			(at 346.71 71.12 0)
			(effects
				(font
					(size 1.27 1.27)
					(thickness 0.15)
				)
				(justify left bottom)
				(hide yes)
			)
		)
		(property "Author" "Antmicro"
			(at 349.25 71.12 0)
			(effects
				(font
					(size 1.27 1.27)
					(thickness 0.15)
				)
				(justify left bottom)
				(hide yes)
			)
		)
		(property "Tolerance" "1%"
			(at 331.47 71.12 0)
			(effects
				(font
					(size 1.27 1.27)
				)
				(justify left bottom)
				(hide yes)
			)
		)
		(pin "1"
		)
		(pin "2"
		)
		(instances
			(project "jetson-agx-thor-baseboard"
				(path ""
					(reference "R271")
					(unit 1)
				)
			)
		)
	)
	(symbol
		(lib_id "antmicropower:GND")
		(at 162.56 106.68 0)
		(unit 1)
		(exclude_from_sim no)
		(in_bom yes)
		(on_board yes)
		(dnp no)
		(property "Reference" "#PWR0485"
			(at 162.56 113.03 0)
			(effects
				(font
					(size 1.27 1.27)
				)
				(justify left bottom)
				(hide yes)
			)
		)
		(property "Value" "GND"
			(at 162.56 110.49 0)
			(effects
				(font
					(size 1.27 1.27)
					(thickness 0.15)
				)
			)
		)
		(property "Footprint" ""
			(at 171.45 114.3 0)
			(effects
				(font
					(size 1.27 1.27)
					(thickness 0.15)
				)
				(justify left bottom)
				(hide yes)
			)
		)
		(property "Datasheet" ""
			(at 171.45 119.38 0)
			(effects
				(font
					(size 1.27 1.27)
					(thickness 0.15)
				)
				(justify left bottom)
				(hide yes)
			)
		)
		(property "Description" ""
			(at 162.56 106.68 0)
			(effects
				(font
					(size 1.27 1.27)
				)
				(hide yes)
			)
		)
		(property "Author" "Antmicro"
			(at 171.45 114.3 0)
			(effects
				(font
					(size 1.27 1.27)
					(thickness 0.15)
				)
				(justify left bottom)
				(hide yes)
			)
		)
		(property "License" "Apache-2.0"
			(at 171.45 116.84 0)
			(effects
				(font
					(size 1.27 1.27)
					(thickness 0.15)
				)
				(justify left bottom)
				(hide yes)
			)
		)
		(pin "1"
		)
		(instances
			(project "jetson-agx-thor-baseboard"
				(path ""
					(reference "#PWR0485")
					(unit 1)
				)
			)
		)
	)
	(symbol
		(lib_id "antmicroResistors0402:R_0R_0402")
		(at 130.81 175.26 0)
		(unit 1)
		(exclude_from_sim no)
		(in_bom no)
		(on_board yes)
		(dnp yes)
		(property "Reference" "R283"
			(at 135.89 174.625 0)
			(effects
				(font
					(size 1.27 1.27)
				)
				(justify left bottom)
			)
		)
		(property "Value" "R_0R_0402"
			(at 151.13 187.96 0)
			(effects
				(font
					(size 1.27 1.27)
					(thickness 0.15)
				)
				(justify left bottom)
				(hide yes)
			)
		)
		(property "Footprint" "antmicro-footprints:R_0402_1005Metric"
			(at 151.13 190.5 0)
			(effects
				(font
					(size 1.27 1.27)
					(thickness 0.15)
				)
				(justify left bottom)
				(hide yes)
			)
		)
		(property "Datasheet" "https://industrial.panasonic.com/cdbs/www-data/pdf/RDA0000/AOA0000C301.pdf"
			(at 151.13 193.04 0)
			(effects
				(font
					(size 1.27 1.27)
					(thickness 0.15)
				)
				(justify left bottom)
				(hide yes)
			)
		)
		(property "Description" "SMD Chip Resistor, Jumper, 0 ohm, 100 mW, 0402 [1005 Metric], Thick Film, General Purpose"
			(at 130.81 175.26 0)
			(effects
				(font
					(size 1.27 1.27)
				)
				(hide yes)
			)
		)
		(property "Manufacturer" "Panasonic"
			(at 151.13 198.12 0)
			(effects
				(font
					(size 1.27 1.27)
					(thickness 0.15)
				)
				(justify left bottom)
				(hide yes)
			)
		)
		(property "MPN" "ERJ2GE0R00X"
			(at 151.13 195.58 0)
			(effects
				(font
					(size 1.27 1.27)
					(thickness 0.15)
				)
				(justify left bottom)
				(hide yes)
			)
		)
		(property "Val" "0R"
			(at 128.27 174.625 0)
			(effects
				(font
					(size 1.27 1.27)
					(thickness 0.15)
				)
				(justify left bottom)
			)
		)
		(property "License" "Apache-2.0"
			(at 151.13 200.66 0)
			(effects
				(font
					(size 1.27 1.27)
					(thickness 0.15)
				)
				(justify left bottom)
				(hide yes)
			)
		)
		(property "Author" "Antmicro"
			(at 151.13 203.2 0)
			(effects
				(font
					(size 1.27 1.27)
					(thickness 0.15)
				)
				(justify left bottom)
				(hide yes)
			)
		)
		(property "Tolerance" "~"
			(at 151.13 185.42 0)
			(effects
				(font
					(size 1.27 1.27)
				)
				(justify left bottom)
				(hide yes)
			)
		)
		(property "Current" "1A"
			(at 151.13 205.74 0)
			(effects
				(font
					(size 1.27 1.27)
					(thickness 0.15)
				)
				(justify left bottom)
				(hide yes)
			)
		)
		(pin "1"
		)
		(pin "2"
		)
		(instances
			(project "jetson-agx-thor-baseboard"
				(path ""
					(reference "R283")
					(unit 1)
				)
			)
		)
	)
	(symbol
		(lib_id "antmicroTestPoints:TP_0.75mm_SMD")
		(at 223.52 121.92 0)
		(unit 1)
		(exclude_from_sim no)
		(in_bom no)
		(on_board yes)
		(dnp no)
		(property "Reference" "TP46"
			(at 227.33 121.92 0)
			(effects
				(font
					(size 1.27 1.27)
				)
				(justify left)
			)
		)
		(property "Value" "TP_0.75mm_SMD"
			(at 233.68 125.73 0)
			(effects
				(font
					(size 1.27 1.27)
					(thickness 0.15)
				)
				(justify left bottom)
				(hide yes)
			)
		)
		(property "Footprint" "antmicro-footprints:TP_SMD_0.75mm"
			(at 233.68 128.27 0)
			(effects
				(font
					(size 1.27 1.27)
					(thickness 0.15)
				)
				(justify left bottom)
				(hide yes)
			)
		)
		(property "Datasheet" ""
			(at 241.3 134.62 0)
			(effects
				(font
					(size 1.27 1.27)
					(thickness 0.15)
				)
				(justify left bottom)
				(hide yes)
			)
		)
		(property "Description" "SMT test point"
			(at 223.52 121.92 0)
			(effects
				(font
					(size 1.27 1.27)
				)
				(hide yes)
			)
		)
		(property "MPN" ""
			(at 234.315 133.35 0)
			(effects
				(font
					(size 1.27 1.27)
					(thickness 0.15)
				)
				(justify left bottom)
				(hide yes)
			)
		)
		(property "Manufacturer" ""
			(at 234.315 128.27 0)
			(effects
				(font
					(size 1.27 1.27)
					(thickness 0.15)
				)
				(justify left bottom)
				(hide yes)
			)
		)
		(property "Author" "Antmicro"
			(at 233.68 130.81 0)
			(effects
				(font
					(size 1.27 1.27)
					(thickness 0.15)
				)
				(justify left bottom)
				(hide yes)
			)
		)
		(property "License" "Apache-2.0"
			(at 233.68 133.35 0)
			(effects
				(font
					(size 1.27 1.27)
					(thickness 0.15)
				)
				(justify left bottom)
				(hide yes)
			)
		)
		(pin "1"
		)
		(instances
			(project "jetson-agx-thor-baseboard"
				(path ""
					(reference "TP46")
					(unit 1)
				)
			)
		)
	)
	(symbol
		(lib_id "antmicropower:GND")
		(at 302.26 92.71 0)
		(unit 1)
		(exclude_from_sim no)
		(in_bom yes)
		(on_board yes)
		(dnp no)
		(property "Reference" "#PWR0479"
			(at 302.26 99.06 0)
			(effects
				(font
					(size 1.27 1.27)
				)
				(justify left bottom)
				(hide yes)
			)
		)
		(property "Value" "GND"
			(at 302.26 96.52 0)
			(effects
				(font
					(size 1.27 1.27)
					(thickness 0.15)
				)
			)
		)
		(property "Footprint" ""
			(at 311.15 100.33 0)
			(effects
				(font
					(size 1.27 1.27)
					(thickness 0.15)
				)
				(justify left bottom)
				(hide yes)
			)
		)
		(property "Datasheet" ""
			(at 311.15 105.41 0)
			(effects
				(font
					(size 1.27 1.27)
					(thickness 0.15)
				)
				(justify left bottom)
				(hide yes)
			)
		)
		(property "Description" ""
			(at 302.26 92.71 0)
			(effects
				(font
					(size 1.27 1.27)
				)
				(hide yes)
			)
		)
		(property "Author" "Antmicro"
			(at 311.15 100.33 0)
			(effects
				(font
					(size 1.27 1.27)
					(thickness 0.15)
				)
				(justify left bottom)
				(hide yes)
			)
		)
		(property "License" "Apache-2.0"
			(at 311.15 102.87 0)
			(effects
				(font
					(size 1.27 1.27)
					(thickness 0.15)
				)
				(justify left bottom)
				(hide yes)
			)
		)
		(pin "1"
		)
		(instances
			(project "jetson-agx-thor-baseboard"
				(path ""
					(reference "#PWR0479")
					(unit 1)
				)
			)
		)
	)
	(symbol
		(lib_id "antmicropower:GND")
		(at 321.31 99.06 0)
		(unit 1)
		(exclude_from_sim no)
		(in_bom yes)
		(on_board yes)
		(dnp no)
		(property "Reference" "#PWR0480"
			(at 321.31 105.41 0)
			(effects
				(font
					(size 1.27 1.27)
				)
				(justify left bottom)
				(hide yes)
			)
		)
		(property "Value" "GND"
			(at 321.31 102.87 0)
			(effects
				(font
					(size 1.27 1.27)
					(thickness 0.15)
				)
			)
		)
		(property "Footprint" ""
			(at 330.2 106.68 0)
			(effects
				(font
					(size 1.27 1.27)
					(thickness 0.15)
				)
				(justify left bottom)
				(hide yes)
			)
		)
		(property "Datasheet" ""
			(at 330.2 111.76 0)
			(effects
				(font
					(size 1.27 1.27)
					(thickness 0.15)
				)
				(justify left bottom)
				(hide yes)
			)
		)
		(property "Description" ""
			(at 321.31 99.06 0)
			(effects
				(font
					(size 1.27 1.27)
				)
				(hide yes)
			)
		)
		(property "Author" "Antmicro"
			(at 330.2 106.68 0)
			(effects
				(font
					(size 1.27 1.27)
					(thickness 0.15)
				)
				(justify left bottom)
				(hide yes)
			)
		)
		(property "License" "Apache-2.0"
			(at 330.2 109.22 0)
			(effects
				(font
					(size 1.27 1.27)
					(thickness 0.15)
				)
				(justify left bottom)
				(hide yes)
			)
		)
		(pin "1"
		)
		(instances
			(project "jetson-agx-thor-baseboard"
				(path ""
					(reference "#PWR0480")
					(unit 1)
				)
			)
		)
	)
	(symbol
		(lib_id "antmicropower:+3V3")
		(at 217.17 105.41 0)
		(mirror y)
		(unit 1)
		(exclude_from_sim no)
		(in_bom yes)
		(on_board yes)
		(dnp no)
		(property "Reference" "#PWR0637"
			(at 217.17 109.22 0)
			(effects
				(font
					(size 1.27 1.27)
				)
				(justify left bottom)
				(hide yes)
			)
		)
		(property "Value" "+3V3"
			(at 213.995 101.6 0)
			(effects
				(font
					(size 1.27 1.27)
					(thickness 0.15)
				)
				(justify right)
			)
		)
		(property "Footprint" ""
			(at 201.93 113.03 0)
			(effects
				(font
					(size 1.27 1.27)
					(thickness 0.15)
				)
				(justify left bottom)
				(hide yes)
			)
		)
		(property "Datasheet" ""
			(at 201.93 115.57 0)
			(effects
				(font
					(size 1.27 1.27)
					(thickness 0.15)
				)
				(justify left bottom)
				(hide yes)
			)
		)
		(property "Description" ""
			(at 217.17 105.41 0)
			(effects
				(font
					(size 1.27 1.27)
				)
				(hide yes)
			)
		)
		(property "Author" "Antmicro"
			(at 201.93 107.95 0)
			(effects
				(font
					(size 1.27 1.27)
					(thickness 0.15)
				)
				(justify left bottom)
				(hide yes)
			)
		)
		(property "License" "Apache-2.0"
			(at 201.93 110.49 0)
			(effects
				(font
					(size 1.27 1.27)
					(thickness 0.15)
				)
				(justify left bottom)
				(hide yes)
			)
		)
		(pin "1"
		)
		(instances
			(project "jetson-agx-thor-baseboard"
				(path ""
					(reference "#PWR0637")
					(unit 1)
				)
			)
		)
	)
	(symbol
		(lib_id "antmicropower:+5V")
		(at 82.55 173.99 0)
		(unit 1)
		(exclude_from_sim no)
		(in_bom yes)
		(on_board yes)
		(dnp no)
		(property "Reference" "#PWR0484"
			(at 82.55 177.8 0)
			(effects
				(font
					(size 1.27 1.27)
				)
				(justify left bottom)
				(hide yes)
			)
		)
		(property "Value" "+5V"
			(at 80.645 170.18 0)
			(effects
				(font
					(size 1.27 1.27)
					(thickness 0.15)
				)
				(justify left)
			)
		)
		(property "Footprint" ""
			(at 97.79 181.61 0)
			(effects
				(font
					(size 1.27 1.27)
					(thickness 0.15)
				)
				(justify left bottom)
				(hide yes)
			)
		)
		(property "Datasheet" ""
			(at 97.79 184.15 0)
			(effects
				(font
					(size 1.27 1.27)
					(thickness 0.15)
				)
				(justify left bottom)
				(hide yes)
			)
		)
		(property "Description" ""
			(at 82.55 173.99 0)
			(effects
				(font
					(size 1.27 1.27)
				)
				(hide yes)
			)
		)
		(property "Author" "Antmicro"
			(at 97.79 181.61 0)
			(effects
				(font
					(size 1.27 1.27)
					(thickness 0.15)
				)
				(justify left bottom)
				(hide yes)
			)
		)
		(property "License" "Apache-2.0"
			(at 97.79 184.15 0)
			(effects
				(font
					(size 1.27 1.27)
					(thickness 0.15)
				)
				(justify left bottom)
				(hide yes)
			)
		)
		(pin "1"
		)
		(instances
			(project "jetson-agx-thor-baseboard"
				(path ""
					(reference "#PWR0484")
					(unit 1)
				)
			)
		)
	)
	(symbol
		(lib_id "antmicroResistors0402:R_10k_0402")
		(at 209.55 111.76 90)
		(unit 1)
		(exclude_from_sim no)
		(in_bom yes)
		(on_board yes)
		(dnp no)
		(property "Reference" "R256"
			(at 210.82 107.95 90)
			(effects
				(font
					(size 1.27 1.27)
				)
				(justify right)
			)
		)
		(property "Value" "R_10k_0402"
			(at 222.25 91.44 0)
			(effects
				(font
					(size 1.27 1.27)
					(thickness 0.15)
				)
				(justify left bottom)
				(hide yes)
			)
		)
		(property "Footprint" "antmicro-footprints:R_0402_1005Metric"
			(at 224.79 91.44 0)
			(effects
				(font
					(size 1.27 1.27)
					(thickness 0.15)
				)
				(justify left bottom)
				(hide yes)
			)
		)
		(property "Datasheet" "https://www.bourns.com/docs/product-datasheets/cr.pdf"
			(at 227.33 91.44 0)
			(effects
				(font
					(size 1.27 1.27)
					(thickness 0.15)
				)
				(justify left bottom)
				(hide yes)
			)
		)
		(property "Description" "SMD Chip Resistor, 10 kohm, ± 1%, 62.5 mW, 0402 [1005 Metric], Thick Film, General Purpose"
			(at 209.55 111.76 0)
			(effects
				(font
					(size 1.27 1.27)
				)
				(hide yes)
			)
		)
		(property "Manufacturer" "Bourns"
			(at 232.41 91.44 0)
			(effects
				(font
					(size 1.27 1.27)
					(thickness 0.15)
				)
				(justify left bottom)
				(hide yes)
			)
		)
		(property "MPN" "CR0402-FX-1002GLF"
			(at 229.87 91.44 0)
			(effects
				(font
					(size 1.27 1.27)
					(thickness 0.15)
				)
				(justify left bottom)
				(hide yes)
			)
		)
		(property "Val" "10k"
			(at 210.82 110.49 90)
			(effects
				(font
					(size 1.27 1.27)
					(thickness 0.15)
				)
				(justify right)
			)
		)
		(property "License" "Apache-2.0"
			(at 234.95 91.44 0)
			(effects
				(font
					(size 1.27 1.27)
					(thickness 0.15)
				)
				(justify left bottom)
				(hide yes)
			)
		)
		(property "Author" "Antmicro"
			(at 237.49 91.44 0)
			(effects
				(font
					(size 1.27 1.27)
					(thickness 0.15)
				)
				(justify left bottom)
				(hide yes)
			)
		)
		(property "Tolerance" "1%"
			(at 219.71 91.44 0)
			(effects
				(font
					(size 1.27 1.27)
				)
				(justify left bottom)
				(hide yes)
			)
		)
		(pin "1"
		)
		(pin "2"
		)
		(instances
			(project "jetson-agx-thor-baseboard"
				(path ""
					(reference "R256")
					(unit 1)
				)
			)
		)
	)
	(symbol
		(lib_id "antmicropower:GND")
		(at 82.55 189.23 0)
		(unit 1)
		(exclude_from_sim no)
		(in_bom yes)
		(on_board yes)
		(dnp no)
		(property "Reference" "#PWR0486"
			(at 82.55 195.58 0)
			(effects
				(font
					(size 1.27 1.27)
				)
				(justify left bottom)
				(hide yes)
			)
		)
		(property "Value" "GND"
			(at 82.55 193.04 0)
			(effects
				(font
					(size 1.27 1.27)
					(thickness 0.15)
				)
			)
		)
		(property "Footprint" ""
			(at 91.44 196.85 0)
			(effects
				(font
					(size 1.27 1.27)
					(thickness 0.15)
				)
				(justify left bottom)
				(hide yes)
			)
		)
		(property "Datasheet" ""
			(at 91.44 201.93 0)
			(effects
				(font
					(size 1.27 1.27)
					(thickness 0.15)
				)
				(justify left bottom)
				(hide yes)
			)
		)
		(property "Description" ""
			(at 82.55 189.23 0)
			(effects
				(font
					(size 1.27 1.27)
				)
				(hide yes)
			)
		)
		(property "Author" "Antmicro"
			(at 91.44 196.85 0)
			(effects
				(font
					(size 1.27 1.27)
					(thickness 0.15)
				)
				(justify left bottom)
				(hide yes)
			)
		)
		(property "License" "Apache-2.0"
			(at 91.44 199.39 0)
			(effects
				(font
					(size 1.27 1.27)
					(thickness 0.15)
				)
				(justify left bottom)
				(hide yes)
			)
		)
		(pin "1"
		)
		(instances
			(project "jetson-agx-thor-baseboard"
				(path ""
					(reference "#PWR0486")
					(unit 1)
				)
			)
		)
	)
	(symbol
		(lib_id "antmicroCapacitors0402:C_100n_0402")
		(at 140.97 100.33 90)
		(mirror x)
		(unit 1)
		(exclude_from_sim no)
		(in_bom yes)
		(on_board yes)
		(dnp no)
		(fields_autoplaced yes)
		(property "Reference" "C117"
			(at 143.51 101.6063 90)
			(effects
				(font
					(size 1.27 1.27)
				)
				(justify right)
			)
		)
		(property "Value" "C_100n_0402"
			(at 151.13 120.65 0)
			(effects
				(font
					(size 1.27 1.27)
					(thickness 0.15)
				)
				(justify left bottom)
				(hide yes)
			)
		)
		(property "Footprint" "antmicro-footprints:C_0402_1005Metric"
			(at 153.67 120.65 0)
			(effects
				(font
					(size 1.27 1.27)
					(thickness 0.15)
				)
				(justify left bottom)
				(hide yes)
			)
		)
		(property "Datasheet" "https://www.murata.com/products/productdetail?partno=GRM155R61H104KE14%23"
			(at 156.21 120.65 0)
			(effects
				(font
					(size 1.27 1.27)
					(thickness 0.15)
				)
				(justify left bottom)
				(hide yes)
			)
		)
		(property "Description" "SMD Multilayer Ceramic Capacitor, 0.1 µF, 50 V, 0402 [1005 Metric], ± 10%, X5R, GRM Series"
			(at 140.97 100.33 0)
			(effects
				(font
					(size 1.27 1.27)
				)
				(hide yes)
			)
		)
		(property "Manufacturer" "Murata"
			(at 161.29 120.65 0)
			(effects
				(font
					(size 1.27 1.27)
					(thickness 0.15)
				)
				(justify left bottom)
				(hide yes)
			)
		)
		(property "MPN" "GRM155R61H104KE14D"
			(at 158.75 120.65 0)
			(effects
				(font
					(size 1.27 1.27)
					(thickness 0.15)
				)
				(justify left bottom)
				(hide yes)
			)
		)
		(property "Val" "100n"
			(at 143.51 104.1463 90)
			(effects
				(font
					(size 1.27 1.27)
					(thickness 0.15)
				)
				(justify right)
			)
		)
		(property "License" "Apache-2.0"
			(at 163.83 120.65 0)
			(effects
				(font
					(size 1.27 1.27)
					(thickness 0.15)
				)
				(justify left bottom)
				(hide yes)
			)
		)
		(property "Author" "Antmicro"
			(at 166.37 120.65 0)
			(effects
				(font
					(size 1.27 1.27)
					(thickness 0.15)
				)
				(justify left bottom)
				(hide yes)
			)
		)
		(property "Voltage" "50V"
			(at 168.91 120.65 0)
			(effects
				(font
					(size 1.27 1.27)
				)
				(justify left bottom)
				(hide yes)
			)
		)
		(property "Dielectric" "X5R"
			(at 171.45 120.65 0)
			(effects
				(font
					(size 1.27 1.27)
				)
				(justify left bottom)
				(hide yes)
			)
		)
		(pin "1"
		)
		(pin "2"
		)
		(instances
			(project "jetson-agx-thor-baseboard"
				(path ""
					(reference "C117")
					(unit 1)
				)
			)
		)
	)
	(symbol
		(lib_id "antmicroCapacitors0402:C_100n_0402")
		(at 218.44 160.02 180)
		(unit 1)
		(exclude_from_sim no)
		(in_bom yes)
		(on_board yes)
		(dnp no)
		(property "Reference" "C107"
			(at 222.25 157.988 0)
			(effects
				(font
					(size 1.27 1.27)
				)
				(justify left bottom)
			)
		)
		(property "Value" "C_100n_0402"
			(at 198.12 149.86 0)
			(effects
				(font
					(size 1.27 1.27)
					(thickness 0.15)
				)
				(justify left bottom)
				(hide yes)
			)
		)
		(property "Footprint" "antmicro-footprints:C_0402_1005Metric"
			(at 198.12 147.32 0)
			(effects
				(font
					(size 1.27 1.27)
					(thickness 0.15)
				)
				(justify left bottom)
				(hide yes)
			)
		)
		(property "Datasheet" "https://www.murata.com/products/productdetail?partno=GRM155R61H104KE14%23"
			(at 198.12 144.78 0)
			(effects
				(font
					(size 1.27 1.27)
					(thickness 0.15)
				)
				(justify left bottom)
				(hide yes)
			)
		)
		(property "Description" "SMD Multilayer Ceramic Capacitor, 0.1 µF, 50 V, 0402 [1005 Metric], ± 10%, X5R, GRM Series"
			(at 218.44 160.02 0)
			(effects
				(font
					(size 1.27 1.27)
				)
				(hide yes)
			)
		)
		(property "Manufacturer" "Murata"
			(at 198.12 139.7 0)
			(effects
				(font
					(size 1.27 1.27)
					(thickness 0.15)
				)
				(justify left bottom)
				(hide yes)
			)
		)
		(property "MPN" "GRM155R61H104KE14D"
			(at 198.12 142.24 0)
			(effects
				(font
					(size 1.27 1.27)
					(thickness 0.15)
				)
				(justify left bottom)
				(hide yes)
			)
		)
		(property "Val" "100n"
			(at 214.63 160.655 0)
			(effects
				(font
					(size 1.27 1.27)
					(thickness 0.15)
				)
				(justify left bottom)
			)
		)
		(property "License" "Apache-2.0"
			(at 198.12 137.16 0)
			(effects
				(font
					(size 1.27 1.27)
					(thickness 0.15)
				)
				(justify left bottom)
				(hide yes)
			)
		)
		(property "Author" "Antmicro"
			(at 198.12 134.62 0)
			(effects
				(font
					(size 1.27 1.27)
					(thickness 0.15)
				)
				(justify left bottom)
				(hide yes)
			)
		)
		(property "Voltage" "50V"
			(at 198.12 132.08 0)
			(effects
				(font
					(size 1.27 1.27)
				)
				(justify left bottom)
				(hide yes)
			)
		)
		(property "Dielectric" "X5R"
			(at 198.12 129.54 0)
			(effects
				(font
					(size 1.27 1.27)
				)
				(justify left bottom)
				(hide yes)
			)
		)
		(pin "1"
		)
		(pin "2"
		)
		(instances
			(project "jetson-agx-thor-baseboard"
				(path ""
					(reference "C107")
					(unit 1)
				)
			)
		)
	)
	(symbol
		(lib_id "antmicroCapacitors0402:C_10u_0402")
		(at 153.67 100.33 90)
		(mirror x)
		(unit 1)
		(exclude_from_sim no)
		(in_bom yes)
		(on_board yes)
		(dnp no)
		(fields_autoplaced yes)
		(property "Reference" "C231"
			(at 156.21 101.6063 90)
			(effects
				(font
					(size 1.27 1.27)
				)
				(justify right)
			)
		)
		(property "Value" "C_10u_0402"
			(at 163.83 120.65 0)
			(effects
				(font
					(size 1.27 1.27)
					(thickness 0.15)
				)
				(justify left bottom)
				(hide yes)
			)
		)
		(property "Footprint" "antmicro-footprints:C_0402_1005Metric"
			(at 166.37 120.65 0)
			(effects
				(font
					(size 1.27 1.27)
					(thickness 0.15)
				)
				(justify left bottom)
				(hide yes)
			)
		)
		(property "Datasheet" "https://www.yageo.com/en/Chart/Download/pdf/CC0402MRX5R5BB106"
			(at 168.91 120.65 0)
			(effects
				(font
					(size 1.27 1.27)
					(thickness 0.15)
				)
				(justify left bottom)
				(hide yes)
			)
		)
		(property "Description" "SMD Multilayer Ceramic Capacitor, 10 µF, 6.3 V, 0402 [1005 Metric], ± 20%, X5R, CC Series"
			(at 153.67 100.33 0)
			(effects
				(font
					(size 1.27 1.27)
				)
				(hide yes)
			)
		)
		(property "Manufacturer" "YAGEO"
			(at 173.99 120.65 0)
			(effects
				(font
					(size 1.27 1.27)
					(thickness 0.15)
				)
				(justify left bottom)
				(hide yes)
			)
		)
		(property "MPN" "CC0402MRX5R5BB106"
			(at 171.45 120.65 0)
			(effects
				(font
					(size 1.27 1.27)
					(thickness 0.15)
				)
				(justify left bottom)
				(hide yes)
			)
		)
		(property "Val" "10u"
			(at 156.21 104.1463 90)
			(effects
				(font
					(size 1.27 1.27)
					(thickness 0.15)
				)
				(justify right)
			)
		)
		(property "License" "Apache-2.0"
			(at 176.53 120.65 0)
			(effects
				(font
					(size 1.27 1.27)
					(thickness 0.15)
				)
				(justify left bottom)
				(hide yes)
			)
		)
		(property "Author" "Antmicro"
			(at 179.07 120.65 0)
			(effects
				(font
					(size 1.27 1.27)
					(thickness 0.15)
				)
				(justify left bottom)
				(hide yes)
			)
		)
		(property "Voltage" ""
			(at 181.61 120.65 0)
			(effects
				(font
					(size 1.27 1.27)
				)
				(justify left bottom)
				(hide yes)
			)
		)
		(property "Dielectric" "template_dielectric"
			(at 184.15 120.65 0)
			(effects
				(font
					(size 1.27 1.27)
				)
				(justify left bottom)
				(hide yes)
			)
		)
		(pin "1"
		)
		(pin "2"
		)
		(instances
			(project "jetson-agx-thor-baseboard"
				(path ""
					(reference "C231")
					(unit 1)
				)
			)
		)
	)
	(symbol
		(lib_id "antmicroResistors0402:R_10k_0402")
		(at 337.82 67.31 270)
		(unit 1)
		(exclude_from_sim no)
		(in_bom yes)
		(on_board yes)
		(dnp no)
		(property "Reference" "R338"
			(at 339.09 68.58 90)
			(effects
				(font
					(size 1.27 1.27)
				)
				(justify left)
			)
		)
		(property "Value" "R_10k_0402"
			(at 325.12 87.63 0)
			(effects
				(font
					(size 1.27 1.27)
					(thickness 0.15)
				)
				(justify left bottom)
				(hide yes)
			)
		)
		(property "Footprint" "antmicro-footprints:R_0402_1005Metric"
			(at 322.58 87.63 0)
			(effects
				(font
					(size 1.27 1.27)
					(thickness 0.15)
				)
				(justify left bottom)
				(hide yes)
			)
		)
		(property "Datasheet" "https://www.bourns.com/docs/product-datasheets/cr.pdf"
			(at 320.04 87.63 0)
			(effects
				(font
					(size 1.27 1.27)
					(thickness 0.15)
				)
				(justify left bottom)
				(hide yes)
			)
		)
		(property "Description" "SMD Chip Resistor, 10 kohm, ± 1%, 62.5 mW, 0402 [1005 Metric], Thick Film, General Purpose"
			(at 337.82 67.31 0)
			(effects
				(font
					(size 1.27 1.27)
				)
				(hide yes)
			)
		)
		(property "Manufacturer" "Bourns"
			(at 314.96 87.63 0)
			(effects
				(font
					(size 1.27 1.27)
					(thickness 0.15)
				)
				(justify left bottom)
				(hide yes)
			)
		)
		(property "MPN" "CR0402-FX-1002GLF"
			(at 317.5 87.63 0)
			(effects
				(font
					(size 1.27 1.27)
					(thickness 0.15)
				)
				(justify left bottom)
				(hide yes)
			)
		)
		(property "Val" "10k"
			(at 339.09 71.12 90)
			(effects
				(font
					(size 1.27 1.27)
					(thickness 0.15)
				)
				(justify left)
			)
		)
		(property "License" "Apache-2.0"
			(at 312.42 87.63 0)
			(effects
				(font
					(size 1.27 1.27)
					(thickness 0.15)
				)
				(justify left bottom)
				(hide yes)
			)
		)
		(property "Author" "Antmicro"
			(at 309.88 87.63 0)
			(effects
				(font
					(size 1.27 1.27)
					(thickness 0.15)
				)
				(justify left bottom)
				(hide yes)
			)
		)
		(property "Tolerance" "1%"
			(at 327.66 87.63 0)
			(effects
				(font
					(size 1.27 1.27)
				)
				(justify left bottom)
				(hide yes)
			)
		)
		(pin "1"
		)
		(pin "2"
		)
		(instances
			(project "jetson-agx-thor-baseboard"
				(path ""
					(reference "R338")
					(unit 1)
				)
			)
		)
	)
	(symbol
		(lib_id "antmicroResistors0402:R_0R_0402")
		(at 130.81 172.72 0)
		(unit 1)
		(exclude_from_sim no)
		(in_bom no)
		(on_board yes)
		(dnp yes)
		(property "Reference" "R282"
			(at 135.89 172.085 0)
			(effects
				(font
					(size 1.27 1.27)
				)
				(justify left bottom)
			)
		)
		(property "Value" "R_0R_0402"
			(at 151.13 185.42 0)
			(effects
				(font
					(size 1.27 1.27)
					(thickness 0.15)
				)
				(justify left bottom)
				(hide yes)
			)
		)
		(property "Footprint" "antmicro-footprints:R_0402_1005Metric"
			(at 151.13 187.96 0)
			(effects
				(font
					(size 1.27 1.27)
					(thickness 0.15)
				)
				(justify left bottom)
				(hide yes)
			)
		)
		(property "Datasheet" "https://industrial.panasonic.com/cdbs/www-data/pdf/RDA0000/AOA0000C301.pdf"
			(at 151.13 190.5 0)
			(effects
				(font
					(size 1.27 1.27)
					(thickness 0.15)
				)
				(justify left bottom)
				(hide yes)
			)
		)
		(property "Description" "SMD Chip Resistor, Jumper, 0 ohm, 100 mW, 0402 [1005 Metric], Thick Film, General Purpose"
			(at 130.81 172.72 0)
			(effects
				(font
					(size 1.27 1.27)
				)
				(hide yes)
			)
		)
		(property "Manufacturer" "Panasonic"
			(at 151.13 195.58 0)
			(effects
				(font
					(size 1.27 1.27)
					(thickness 0.15)
				)
				(justify left bottom)
				(hide yes)
			)
		)
		(property "MPN" "ERJ2GE0R00X"
			(at 151.13 193.04 0)
			(effects
				(font
					(size 1.27 1.27)
					(thickness 0.15)
				)
				(justify left bottom)
				(hide yes)
			)
		)
		(property "Val" "0R"
			(at 128.27 172.085 0)
			(effects
				(font
					(size 1.27 1.27)
					(thickness 0.15)
				)
				(justify left bottom)
			)
		)
		(property "License" "Apache-2.0"
			(at 151.13 198.12 0)
			(effects
				(font
					(size 1.27 1.27)
					(thickness 0.15)
				)
				(justify left bottom)
				(hide yes)
			)
		)
		(property "Author" "Antmicro"
			(at 151.13 200.66 0)
			(effects
				(font
					(size 1.27 1.27)
					(thickness 0.15)
				)
				(justify left bottom)
				(hide yes)
			)
		)
		(property "Tolerance" "~"
			(at 151.13 182.88 0)
			(effects
				(font
					(size 1.27 1.27)
				)
				(justify left bottom)
				(hide yes)
			)
		)
		(property "Current" "1A"
			(at 151.13 203.2 0)
			(effects
				(font
					(size 1.27 1.27)
					(thickness 0.15)
				)
				(justify left bottom)
				(hide yes)
			)
		)
		(pin "1"
		)
		(pin "2"
		)
		(instances
			(project "jetson-agx-thor-baseboard"
				(path ""
					(reference "R282")
					(unit 1)
				)
			)
		)
	)
	(symbol
		(lib_id "antmicroTransistorsFETsMOSFETsSingle:DMG1012T-7")
		(at 331.47 85.09 0)
		(unit 1)
		(exclude_from_sim no)
		(in_bom yes)
		(on_board yes)
		(dnp no)
		(fields_autoplaced yes)
		(property "Reference" "Q15"
			(at 341.63 81.28 0)
			(effects
				(font
					(size 1.27 1.27)
					(thickness 0.15)
				)
				(justify left)
			)
		)
		(property "Value" "DMG1012T-7"
			(at 354.33 93.98 0)
			(effects
				(font
					(size 1.27 1.27)
					(thickness 0.15)
				)
				(justify left bottom)
				(hide yes)
			)
		)
		(property "Footprint" "antmicro-footprints:SOT-523"
			(at 354.33 96.52 0)
			(effects
				(font
					(size 1.27 1.27)
					(thickness 0.15)
				)
				(justify left bottom)
				(hide yes)
			)
		)
		(property "Datasheet" "https://www.diodes.com/assets/Datasheets/ds31783.pdf"
			(at 354.33 99.06 0)
			(effects
				(font
					(size 1.27 1.27)
					(thickness 0.15)
				)
				(justify left bottom)
				(hide yes)
			)
		)
		(property "Description" "Power MOSFET, N Channel, 20 V, 630 mA, 0.3 ohm, SOT-523, Surface Mount"
			(at 354.33 111.76 0)
			(effects
				(font
					(size 1.27 1.27)
				)
				(justify left bottom)
				(hide yes)
			)
		)
		(property "MPN" "DMG1012T-7"
			(at 341.63 83.82 0)
			(effects
				(font
					(size 1.27 1.27)
					(thickness 0.15)
				)
				(justify left)
			)
		)
		(property "Manufacturer" "Diodes Incorporated"
			(at 354.33 104.14 0)
			(effects
				(font
					(size 1.27 1.27)
					(thickness 0.15)
				)
				(justify left bottom)
				(hide yes)
			)
		)
		(property "Author" "Antmicro"
			(at 354.33 106.68 0)
			(effects
				(font
					(size 1.27 1.27)
					(thickness 0.15)
				)
				(justify left bottom)
				(hide yes)
			)
		)
		(property "License" "Apache-2.0"
			(at 354.33 109.22 0)
			(effects
				(font
					(size 1.27 1.27)
					(thickness 0.15)
				)
				(justify left bottom)
				(hide yes)
			)
		)
		(pin "3"
		)
		(pin "1"
		)
		(pin "2"
		)
		(instances
			(project "jetson-agx-thor-baseboard"
				(path ""
					(reference "Q15")
					(unit 1)
				)
			)
		)
	)
	(symbol
		(lib_id "antmicropower:+3V3")
		(at 218.44 81.28 0)
		(unit 1)
		(exclude_from_sim no)
		(in_bom yes)
		(on_board yes)
		(dnp no)
		(property "Reference" "#PWR0463"
			(at 218.44 85.09 0)
			(effects
				(font
					(size 1.27 1.27)
				)
				(justify left bottom)
				(hide yes)
			)
		)
		(property "Value" "+3V3"
			(at 215.265 77.47 0)
			(effects
				(font
					(size 1.27 1.27)
					(thickness 0.15)
				)
				(justify left)
			)
		)
		(property "Footprint" ""
			(at 233.68 88.9 0)
			(effects
				(font
					(size 1.27 1.27)
					(thickness 0.15)
				)
				(justify left bottom)
				(hide yes)
			)
		)
		(property "Datasheet" ""
			(at 233.68 91.44 0)
			(effects
				(font
					(size 1.27 1.27)
					(thickness 0.15)
				)
				(justify left bottom)
				(hide yes)
			)
		)
		(property "Description" ""
			(at 218.44 81.28 0)
			(effects
				(font
					(size 1.27 1.27)
				)
				(hide yes)
			)
		)
		(property "Author" "Antmicro"
			(at 233.68 83.82 0)
			(effects
				(font
					(size 1.27 1.27)
					(thickness 0.15)
				)
				(justify left bottom)
				(hide yes)
			)
		)
		(property "License" "Apache-2.0"
			(at 233.68 86.36 0)
			(effects
				(font
					(size 1.27 1.27)
					(thickness 0.15)
				)
				(justify left bottom)
				(hide yes)
			)
		)
		(pin "1"
		)
		(instances
			(project "jetson-agx-thor-baseboard"
				(path ""
					(reference "#PWR0463")
					(unit 1)
				)
			)
		)
	)
	(symbol
		(lib_id "antmicropower:GND")
		(at 237.49 81.28 0)
		(unit 1)
		(exclude_from_sim no)
		(in_bom yes)
		(on_board yes)
		(dnp no)
		(property "Reference" "#PWR0465"
			(at 237.49 87.63 0)
			(effects
				(font
					(size 1.27 1.27)
				)
				(justify left bottom)
				(hide yes)
			)
		)
		(property "Value" "GND"
			(at 237.49 85.09 0)
			(effects
				(font
					(size 1.27 1.27)
					(thickness 0.15)
				)
			)
		)
		(property "Footprint" ""
			(at 246.38 88.9 0)
			(effects
				(font
					(size 1.27 1.27)
					(thickness 0.15)
				)
				(justify left bottom)
				(hide yes)
			)
		)
		(property "Datasheet" ""
			(at 246.38 93.98 0)
			(effects
				(font
					(size 1.27 1.27)
					(thickness 0.15)
				)
				(justify left bottom)
				(hide yes)
			)
		)
		(property "Description" ""
			(at 237.49 81.28 0)
			(effects
				(font
					(size 1.27 1.27)
				)
				(hide yes)
			)
		)
		(property "Author" "Antmicro"
			(at 246.38 88.9 0)
			(effects
				(font
					(size 1.27 1.27)
					(thickness 0.15)
				)
				(justify left bottom)
				(hide yes)
			)
		)
		(property "License" "Apache-2.0"
			(at 246.38 91.44 0)
			(effects
				(font
					(size 1.27 1.27)
					(thickness 0.15)
				)
				(justify left bottom)
				(hide yes)
			)
		)
		(pin "1"
		)
		(instances
			(project "jetson-agx-thor-baseboard"
				(path ""
					(reference "#PWR0465")
					(unit 1)
				)
			)
		)
	)
	(symbol
		(lib_id "antmicroTVSDiodes:TPD4E05U06QDQARQ1")
		(at 289.56 119.38 270)
		(mirror x)
		(unit 1)
		(exclude_from_sim no)
		(in_bom yes)
		(on_board yes)
		(dnp no)
		(property "Reference" "U58"
			(at 285.115 106.68 90)
			(effects
				(font
					(size 1.27 1.27)
				)
			)
		)
		(property "Value" "TPD4E05U06QDQARQ1"
			(at 279.4 95.25 0)
			(effects
				(font
					(size 1.27 1.27)
					(thickness 0.15)
				)
				(justify left bottom)
				(hide yes)
			)
		)
		(property "Footprint" "antmicro-footprints:USON-10_2.5x1mm_P0.5mm"
			(at 284.48 95.25 0)
			(effects
				(font
					(size 1.27 1.27)
					(thickness 0.15)
				)
				(justify left bottom)
				(hide yes)
			)
		)
		(property "Datasheet" "https://www.ti.com/lit/ds/symlink/tpd4e05u06-q1.pdf?HQS=dis-mous-null-mousermode-dsf-pf-null-wwe&ts=1663591265741&ref_url=https%253A%252F%252Fwww.mouser.com%252F"
			(at 281.94 95.25 0)
			(effects
				(font
					(size 1.27 1.27)
					(thickness 0.15)
				)
				(justify left bottom)
				(hide yes)
			)
		)
		(property "Description" "TVS diode array, 12 kV, USON-10, 5.5 V, 0.5 pF"
			(at 289.56 119.38 0)
			(effects
				(font
					(size 1.27 1.27)
				)
				(hide yes)
			)
		)
		(property "Manufacturer" "Texas Instruments"
			(at 276.86 95.25 0)
			(effects
				(font
					(size 1.27 1.27)
					(thickness 0.15)
				)
				(justify left bottom)
				(hide yes)
			)
		)
		(property "MPN" "TPD4E05U06QDQARQ1"
			(at 285.115 109.22 90)
			(effects
				(font
					(size 1.27 1.27)
					(thickness 0.15)
				)
			)
		)
		(property "Author" "Antmicro"
			(at 274.32 95.25 0)
			(effects
				(font
					(size 1.27 1.27)
					(thickness 0.15)
				)
				(justify left bottom)
				(hide yes)
			)
		)
		(property "License" "Apache-2.0"
			(at 271.78 95.25 0)
			(effects
				(font
					(size 1.27 1.27)
					(thickness 0.15)
				)
				(justify left bottom)
				(hide yes)
			)
		)
		(pin "1"
		)
		(pin "10"
		)
		(pin "2"
		)
		(pin "3"
		)
		(pin "4"
		)
		(pin "5"
		)
		(pin "6"
		)
		(pin "7"
		)
		(pin "8"
		)
		(pin "9"
		)
		(instances
			(project "jetson-agx-thor-baseboard"
				(path ""
					(reference "U58")
					(unit 1)
				)
			)
		)
	)
	(symbol
		(lib_id "antmicroCapacitors0402:C_100n_0402")
		(at 289.56 86.36 90)
		(mirror x)
		(unit 1)
		(exclude_from_sim no)
		(in_bom yes)
		(on_board yes)
		(dnp no)
		(fields_autoplaced yes)
		(property "Reference" "C116"
			(at 292.1 87.6363 90)
			(effects
				(font
					(size 1.27 1.27)
				)
				(justify right)
			)
		)
		(property "Value" "C_100n_0402"
			(at 299.72 106.68 0)
			(effects
				(font
					(size 1.27 1.27)
					(thickness 0.15)
				)
				(justify left bottom)
				(hide yes)
			)
		)
		(property "Footprint" "antmicro-footprints:C_0402_1005Metric"
			(at 302.26 106.68 0)
			(effects
				(font
					(size 1.27 1.27)
					(thickness 0.15)
				)
				(justify left bottom)
				(hide yes)
			)
		)
		(property "Datasheet" "https://www.murata.com/products/productdetail?partno=GRM155R61H104KE14%23"
			(at 304.8 106.68 0)
			(effects
				(font
					(size 1.27 1.27)
					(thickness 0.15)
				)
				(justify left bottom)
				(hide yes)
			)
		)
		(property "Description" "SMD Multilayer Ceramic Capacitor, 0.1 µF, 50 V, 0402 [1005 Metric], ± 10%, X5R, GRM Series"
			(at 289.56 86.36 0)
			(effects
				(font
					(size 1.27 1.27)
				)
				(hide yes)
			)
		)
		(property "Manufacturer" "Murata"
			(at 309.88 106.68 0)
			(effects
				(font
					(size 1.27 1.27)
					(thickness 0.15)
				)
				(justify left bottom)
				(hide yes)
			)
		)
		(property "MPN" "GRM155R61H104KE14D"
			(at 307.34 106.68 0)
			(effects
				(font
					(size 1.27 1.27)
					(thickness 0.15)
				)
				(justify left bottom)
				(hide yes)
			)
		)
		(property "Val" "100n"
			(at 292.1 90.1763 90)
			(effects
				(font
					(size 1.27 1.27)
					(thickness 0.15)
				)
				(justify right)
			)
		)
		(property "License" "Apache-2.0"
			(at 312.42 106.68 0)
			(effects
				(font
					(size 1.27 1.27)
					(thickness 0.15)
				)
				(justify left bottom)
				(hide yes)
			)
		)
		(property "Author" "Antmicro"
			(at 314.96 106.68 0)
			(effects
				(font
					(size 1.27 1.27)
					(thickness 0.15)
				)
				(justify left bottom)
				(hide yes)
			)
		)
		(property "Voltage" "50V"
			(at 317.5 106.68 0)
			(effects
				(font
					(size 1.27 1.27)
				)
				(justify left bottom)
				(hide yes)
			)
		)
		(property "Dielectric" "X5R"
			(at 320.04 106.68 0)
			(effects
				(font
					(size 1.27 1.27)
				)
				(justify left bottom)
				(hide yes)
			)
		)
		(pin "1"
		)
		(pin "2"
		)
		(instances
			(project "jetson-agx-thor-baseboard"
				(path ""
					(reference "C116")
					(unit 1)
				)
			)
		)
	)
	(symbol
		(lib_id "antmicroResistors0402:R_0R_0402")
		(at 130.81 170.18 0)
		(unit 1)
		(exclude_from_sim no)
		(in_bom no)
		(on_board yes)
		(dnp yes)
		(property "Reference" "R281"
			(at 135.89 169.545 0)
			(effects
				(font
					(size 1.27 1.27)
				)
				(justify left bottom)
			)
		)
		(property "Value" "R_0R_0402"
			(at 151.13 182.88 0)
			(effects
				(font
					(size 1.27 1.27)
					(thickness 0.15)
				)
				(justify left bottom)
				(hide yes)
			)
		)
		(property "Footprint" "antmicro-footprints:R_0402_1005Metric"
			(at 151.13 185.42 0)
			(effects
				(font
					(size 1.27 1.27)
					(thickness 0.15)
				)
				(justify left bottom)
				(hide yes)
			)
		)
		(property "Datasheet" "https://industrial.panasonic.com/cdbs/www-data/pdf/RDA0000/AOA0000C301.pdf"
			(at 151.13 187.96 0)
			(effects
				(font
					(size 1.27 1.27)
					(thickness 0.15)
				)
				(justify left bottom)
				(hide yes)
			)
		)
		(property "Description" "SMD Chip Resistor, Jumper, 0 ohm, 100 mW, 0402 [1005 Metric], Thick Film, General Purpose"
			(at 130.81 170.18 0)
			(effects
				(font
					(size 1.27 1.27)
				)
				(hide yes)
			)
		)
		(property "Manufacturer" "Panasonic"
			(at 151.13 193.04 0)
			(effects
				(font
					(size 1.27 1.27)
					(thickness 0.15)
				)
				(justify left bottom)
				(hide yes)
			)
		)
		(property "MPN" "ERJ2GE0R00X"
			(at 151.13 190.5 0)
			(effects
				(font
					(size 1.27 1.27)
					(thickness 0.15)
				)
				(justify left bottom)
				(hide yes)
			)
		)
		(property "Val" "0R"
			(at 128.27 169.545 0)
			(effects
				(font
					(size 1.27 1.27)
					(thickness 0.15)
				)
				(justify left bottom)
			)
		)
		(property "License" "Apache-2.0"
			(at 151.13 195.58 0)
			(effects
				(font
					(size 1.27 1.27)
					(thickness 0.15)
				)
				(justify left bottom)
				(hide yes)
			)
		)
		(property "Author" "Antmicro"
			(at 151.13 198.12 0)
			(effects
				(font
					(size 1.27 1.27)
					(thickness 0.15)
				)
				(justify left bottom)
				(hide yes)
			)
		)
		(property "Tolerance" "~"
			(at 151.13 180.34 0)
			(effects
				(font
					(size 1.27 1.27)
				)
				(justify left bottom)
				(hide yes)
			)
		)
		(property "Current" "1A"
			(at 151.13 200.66 0)
			(effects
				(font
					(size 1.27 1.27)
					(thickness 0.15)
				)
				(justify left bottom)
				(hide yes)
			)
		)
		(pin "1"
		)
		(pin "2"
		)
		(instances
			(project "jetson-agx-thor-baseboard"
				(path ""
					(reference "R281")
					(unit 1)
				)
			)
		)
	)
	(symbol
		(lib_id "antmicroCapacitors0402:C_100n_0402")
		(at 129.54 160.02 0)
		(mirror x)
		(unit 1)
		(exclude_from_sim no)
		(in_bom yes)
		(on_board yes)
		(dnp no)
		(property "Reference" "C200"
			(at 135.89 158.75 0)
			(effects
				(font
					(size 1.27 1.27)
				)
			)
		)
		(property "Value" "C_100n_0402"
			(at 149.86 149.86 0)
			(effects
				(font
					(size 1.27 1.27)
					(thickness 0.15)
				)
				(justify left bottom)
				(hide yes)
			)
		)
		(property "Footprint" "antmicro-footprints:C_0402_1005Metric"
			(at 149.86 147.32 0)
			(effects
				(font
					(size 1.27 1.27)
					(thickness 0.15)
				)
				(justify left bottom)
				(hide yes)
			)
		)
		(property "Datasheet" "https://www.murata.com/products/productdetail?partno=GRM155R61H104KE14%23"
			(at 149.86 144.78 0)
			(effects
				(font
					(size 1.27 1.27)
					(thickness 0.15)
				)
				(justify left bottom)
				(hide yes)
			)
		)
		(property "Description" "SMD Multilayer Ceramic Capacitor, 0.1 µF, 50 V, 0402 [1005 Metric], ± 10%, X5R, GRM Series"
			(at 129.54 160.02 0)
			(effects
				(font
					(size 1.27 1.27)
				)
				(hide yes)
			)
		)
		(property "Manufacturer" "Murata"
			(at 149.86 139.7 0)
			(effects
				(font
					(size 1.27 1.27)
					(thickness 0.15)
				)
				(justify left bottom)
				(hide yes)
			)
		)
		(property "MPN" "GRM155R61H104KE14D"
			(at 149.86 142.24 0)
			(effects
				(font
					(size 1.27 1.27)
					(thickness 0.15)
				)
				(justify left bottom)
				(hide yes)
			)
		)
		(property "Val" "100n"
			(at 128.27 161.29 0)
			(effects
				(font
					(size 1.27 1.27)
					(thickness 0.15)
				)
			)
		)
		(property "License" "Apache-2.0"
			(at 149.86 137.16 0)
			(effects
				(font
					(size 1.27 1.27)
					(thickness 0.15)
				)
				(justify left bottom)
				(hide yes)
			)
		)
		(property "Author" "Antmicro"
			(at 149.86 134.62 0)
			(effects
				(font
					(size 1.27 1.27)
					(thickness 0.15)
				)
				(justify left bottom)
				(hide yes)
			)
		)
		(property "Voltage" "50V"
			(at 149.86 132.08 0)
			(effects
				(font
					(size 1.27 1.27)
				)
				(justify left bottom)
				(hide yes)
			)
		)
		(property "Dielectric" "X5R"
			(at 149.86 129.54 0)
			(effects
				(font
					(size 1.27 1.27)
				)
				(justify left bottom)
				(hide yes)
			)
		)
		(pin "1"
		)
		(pin "2"
		)
		(instances
			(project "jetson-agx-thor-baseboard"
				(path ""
					(reference "C200")
					(unit 1)
				)
			)
		)
	)
	(symbol
		(lib_id "antmicroResistors0402:R_0R_0402")
		(at 132.08 139.7 0)
		(unit 1)
		(exclude_from_sim no)
		(in_bom yes)
		(on_board yes)
		(dnp no)
		(property "Reference" "R277"
			(at 137.16 139.065 0)
			(effects
				(font
					(size 1.27 1.27)
				)
				(justify left bottom)
			)
		)
		(property "Value" "R_0R_0402"
			(at 152.4 152.4 0)
			(effects
				(font
					(size 1.27 1.27)
					(thickness 0.15)
				)
				(justify left bottom)
				(hide yes)
			)
		)
		(property "Footprint" "antmicro-footprints:R_0402_1005Metric"
			(at 152.4 154.94 0)
			(effects
				(font
					(size 1.27 1.27)
					(thickness 0.15)
				)
				(justify left bottom)
				(hide yes)
			)
		)
		(property "Datasheet" "https://industrial.panasonic.com/cdbs/www-data/pdf/RDA0000/AOA0000C301.pdf"
			(at 152.4 157.48 0)
			(effects
				(font
					(size 1.27 1.27)
					(thickness 0.15)
				)
				(justify left bottom)
				(hide yes)
			)
		)
		(property "Description" "SMD Chip Resistor, Jumper, 0 ohm, 100 mW, 0402 [1005 Metric], Thick Film, General Purpose"
			(at 132.08 139.7 0)
			(effects
				(font
					(size 1.27 1.27)
				)
				(hide yes)
			)
		)
		(property "Manufacturer" "Panasonic"
			(at 152.4 162.56 0)
			(effects
				(font
					(size 1.27 1.27)
					(thickness 0.15)
				)
				(justify left bottom)
				(hide yes)
			)
		)
		(property "MPN" "ERJ2GE0R00X"
			(at 152.4 160.02 0)
			(effects
				(font
					(size 1.27 1.27)
					(thickness 0.15)
				)
				(justify left bottom)
				(hide yes)
			)
		)
		(property "Val" "0R"
			(at 129.54 139.065 0)
			(effects
				(font
					(size 1.27 1.27)
					(thickness 0.15)
				)
				(justify left bottom)
			)
		)
		(property "License" "Apache-2.0"
			(at 152.4 165.1 0)
			(effects
				(font
					(size 1.27 1.27)
					(thickness 0.15)
				)
				(justify left bottom)
				(hide yes)
			)
		)
		(property "Author" "Antmicro"
			(at 152.4 167.64 0)
			(effects
				(font
					(size 1.27 1.27)
					(thickness 0.15)
				)
				(justify left bottom)
				(hide yes)
			)
		)
		(property "Tolerance" "~"
			(at 152.4 149.86 0)
			(effects
				(font
					(size 1.27 1.27)
				)
				(justify left bottom)
				(hide yes)
			)
		)
		(property "Current" "1A"
			(at 152.4 170.18 0)
			(effects
				(font
					(size 1.27 1.27)
					(thickness 0.15)
				)
				(justify left bottom)
				(hide yes)
			)
		)
		(pin "1"
		)
		(pin "2"
		)
		(instances
			(project "jetson-agx-thor-baseboard"
				(path ""
					(reference "R277")
					(unit 1)
				)
			)
		)
	)
	(symbol
		(lib_id "antmicroCapacitors0402:C_100n_0402")
		(at 129.54 152.4 0)
		(mirror x)
		(unit 1)
		(exclude_from_sim no)
		(in_bom yes)
		(on_board yes)
		(dnp no)
		(property "Reference" "C154"
			(at 135.89 151.13 0)
			(effects
				(font
					(size 1.27 1.27)
				)
			)
		)
		(property "Value" "C_100n_0402"
			(at 149.86 142.24 0)
			(effects
				(font
					(size 1.27 1.27)
					(thickness 0.15)
				)
				(justify left bottom)
				(hide yes)
			)
		)
		(property "Footprint" "antmicro-footprints:C_0402_1005Metric"
			(at 149.86 139.7 0)
			(effects
				(font
					(size 1.27 1.27)
					(thickness 0.15)
				)
				(justify left bottom)
				(hide yes)
			)
		)
		(property "Datasheet" "https://www.murata.com/products/productdetail?partno=GRM155R61H104KE14%23"
			(at 149.86 137.16 0)
			(effects
				(font
					(size 1.27 1.27)
					(thickness 0.15)
				)
				(justify left bottom)
				(hide yes)
			)
		)
		(property "Description" "SMD Multilayer Ceramic Capacitor, 0.1 µF, 50 V, 0402 [1005 Metric], ± 10%, X5R, GRM Series"
			(at 129.54 152.4 0)
			(effects
				(font
					(size 1.27 1.27)
				)
				(hide yes)
			)
		)
		(property "Manufacturer" "Murata"
			(at 149.86 132.08 0)
			(effects
				(font
					(size 1.27 1.27)
					(thickness 0.15)
				)
				(justify left bottom)
				(hide yes)
			)
		)
		(property "MPN" "GRM155R61H104KE14D"
			(at 149.86 134.62 0)
			(effects
				(font
					(size 1.27 1.27)
					(thickness 0.15)
				)
				(justify left bottom)
				(hide yes)
			)
		)
		(property "Val" "100n"
			(at 128.27 153.67 0)
			(effects
				(font
					(size 1.27 1.27)
					(thickness 0.15)
				)
			)
		)
		(property "License" "Apache-2.0"
			(at 149.86 129.54 0)
			(effects
				(font
					(size 1.27 1.27)
					(thickness 0.15)
				)
				(justify left bottom)
				(hide yes)
			)
		)
		(property "Author" "Antmicro"
			(at 149.86 127 0)
			(effects
				(font
					(size 1.27 1.27)
					(thickness 0.15)
				)
				(justify left bottom)
				(hide yes)
			)
		)
		(property "Voltage" "50V"
			(at 149.86 124.46 0)
			(effects
				(font
					(size 1.27 1.27)
				)
				(justify left bottom)
				(hide yes)
			)
		)
		(property "Dielectric" "X5R"
			(at 149.86 121.92 0)
			(effects
				(font
					(size 1.27 1.27)
				)
				(justify left bottom)
				(hide yes)
			)
		)
		(pin "1"
		)
		(pin "2"
		)
		(instances
			(project "jetson-agx-thor-baseboard"
				(path ""
					(reference "C154")
					(unit 1)
				)
			)
		)
	)
	(symbol
		(lib_id "antmicropower:+3V3")
		(at 140.97 97.79 0)
		(mirror y)
		(unit 1)
		(exclude_from_sim no)
		(in_bom yes)
		(on_board yes)
		(dnp no)
		(property "Reference" "#PWR0457"
			(at 140.97 101.6 0)
			(effects
				(font
					(size 1.27 1.27)
				)
				(justify left bottom)
				(hide yes)
			)
		)
		(property "Value" "+3V3"
			(at 137.795 93.98 0)
			(effects
				(font
					(size 1.27 1.27)
					(thickness 0.15)
				)
				(justify right)
			)
		)
		(property "Footprint" ""
			(at 125.73 105.41 0)
			(effects
				(font
					(size 1.27 1.27)
					(thickness 0.15)
				)
				(justify left bottom)
				(hide yes)
			)
		)
		(property "Datasheet" ""
			(at 125.73 107.95 0)
			(effects
				(font
					(size 1.27 1.27)
					(thickness 0.15)
				)
				(justify left bottom)
				(hide yes)
			)
		)
		(property "Description" ""
			(at 140.97 97.79 0)
			(effects
				(font
					(size 1.27 1.27)
				)
				(hide yes)
			)
		)
		(property "Author" "Antmicro"
			(at 125.73 100.33 0)
			(effects
				(font
					(size 1.27 1.27)
					(thickness 0.15)
				)
				(justify left bottom)
				(hide yes)
			)
		)
		(property "License" "Apache-2.0"
			(at 125.73 102.87 0)
			(effects
				(font
					(size 1.27 1.27)
					(thickness 0.15)
				)
				(justify left bottom)
				(hide yes)
			)
		)
		(pin "1"
		)
		(instances
			(project "jetson-agx-thor-baseboard"
				(path ""
					(reference "#PWR0457")
					(unit 1)
				)
			)
		)
	)
	(symbol
		(lib_id "antmicropower:GND")
		(at 158.75 181.61 0)
		(mirror y)
		(unit 1)
		(exclude_from_sim no)
		(in_bom yes)
		(on_board yes)
		(dnp no)
		(property "Reference" "#PWR0460"
			(at 158.75 187.96 0)
			(effects
				(font
					(size 1.27 1.27)
				)
				(justify left bottom)
				(hide yes)
			)
		)
		(property "Value" "GND"
			(at 158.75 185.42 0)
			(effects
				(font
					(size 1.27 1.27)
					(thickness 0.15)
				)
			)
		)
		(property "Footprint" ""
			(at 149.86 189.23 0)
			(effects
				(font
					(size 1.27 1.27)
					(thickness 0.15)
				)
				(justify left bottom)
				(hide yes)
			)
		)
		(property "Datasheet" ""
			(at 149.86 194.31 0)
			(effects
				(font
					(size 1.27 1.27)
					(thickness 0.15)
				)
				(justify left bottom)
				(hide yes)
			)
		)
		(property "Description" ""
			(at 158.75 181.61 0)
			(effects
				(font
					(size 1.27 1.27)
				)
				(hide yes)
			)
		)
		(property "Author" "Antmicro"
			(at 149.86 189.23 0)
			(effects
				(font
					(size 1.27 1.27)
					(thickness 0.15)
				)
				(justify left bottom)
				(hide yes)
			)
		)
		(property "License" "Apache-2.0"
			(at 149.86 191.77 0)
			(effects
				(font
					(size 1.27 1.27)
					(thickness 0.15)
				)
				(justify left bottom)
				(hide yes)
			)
		)
		(pin "1"
		)
		(instances
			(project "jetson-agx-thor-baseboard"
				(path ""
					(reference "#PWR0460")
					(unit 1)
				)
			)
		)
	)
	(symbol
		(lib_id "antmicropower:+3V3")
		(at 337.82 63.5 0)
		(unit 1)
		(exclude_from_sim no)
		(in_bom yes)
		(on_board yes)
		(dnp no)
		(property "Reference" "#PWR0636"
			(at 337.82 67.31 0)
			(effects
				(font
					(size 1.27 1.27)
				)
				(justify left bottom)
				(hide yes)
			)
		)
		(property "Value" "+3V3"
			(at 334.645 59.69 0)
			(effects
				(font
					(size 1.27 1.27)
					(thickness 0.15)
				)
				(justify left)
			)
		)
		(property "Footprint" ""
			(at 353.06 71.12 0)
			(effects
				(font
					(size 1.27 1.27)
					(thickness 0.15)
				)
				(justify left bottom)
				(hide yes)
			)
		)
		(property "Datasheet" ""
			(at 353.06 73.66 0)
			(effects
				(font
					(size 1.27 1.27)
					(thickness 0.15)
				)
				(justify left bottom)
				(hide yes)
			)
		)
		(property "Description" ""
			(at 337.82 63.5 0)
			(effects
				(font
					(size 1.27 1.27)
				)
				(hide yes)
			)
		)
		(property "Author" "Antmicro"
			(at 353.06 66.04 0)
			(effects
				(font
					(size 1.27 1.27)
					(thickness 0.15)
				)
				(justify left bottom)
				(hide yes)
			)
		)
		(property "License" "Apache-2.0"
			(at 353.06 68.58 0)
			(effects
				(font
					(size 1.27 1.27)
					(thickness 0.15)
				)
				(justify left bottom)
				(hide yes)
			)
		)
		(pin "1"
		)
		(instances
			(project "jetson-agx-thor-baseboard"
				(path ""
					(reference "#PWR0636")
					(unit 1)
				)
			)
		)
	)
	(symbol
		(lib_id "antmicroResistors0402:R_200k_0402")
		(at 119.38 189.23 0)
		(mirror x)
		(unit 1)
		(exclude_from_sim no)
		(in_bom yes)
		(on_board yes)
		(dnp no)
		(property "Reference" "R280"
			(at 114.3 187.325 0)
			(effects
				(font
					(size 1.27 1.27)
				)
				(justify left bottom)
			)
		)
		(property "Value" "R_200k_0402"
			(at 139.7 176.53 0)
			(effects
				(font
					(size 1.27 1.27)
					(thickness 0.15)
				)
				(justify left bottom)
				(hide yes)
			)
		)
		(property "Footprint" "antmicro-footprints:R_0402_1005Metric"
			(at 139.7 173.99 0)
			(effects
				(font
					(size 1.27 1.27)
					(thickness 0.15)
				)
				(justify left bottom)
				(hide yes)
			)
		)
		(property "Datasheet" "https://www.bourns.com/docs/product-datasheets/cr.pdf"
			(at 139.7 171.45 0)
			(effects
				(font
					(size 1.27 1.27)
					(thickness 0.15)
				)
				(justify left bottom)
				(hide yes)
			)
		)
		(property "Description" "SMD Chip Resistor, 200 kohm, ± 1%, 62.5 mW, 0402 [1005 Metric], Thick Film, General Purpose"
			(at 119.38 189.23 0)
			(effects
				(font
					(size 1.27 1.27)
				)
				(hide yes)
			)
		)
		(property "Manufacturer" "Bourns"
			(at 139.7 166.37 0)
			(effects
				(font
					(size 1.27 1.27)
					(thickness 0.15)
				)
				(justify left bottom)
				(hide yes)
			)
		)
		(property "MPN" "CR0402-FX-2003GLF"
			(at 139.7 168.91 0)
			(effects
				(font
					(size 1.27 1.27)
					(thickness 0.15)
				)
				(justify left bottom)
				(hide yes)
			)
		)
		(property "Val" "200k"
			(at 124.46 187.325 0)
			(effects
				(font
					(size 1.27 1.27)
					(thickness 0.15)
				)
				(justify left bottom)
			)
		)
		(property "License" "Apache-2.0"
			(at 139.7 163.83 0)
			(effects
				(font
					(size 1.27 1.27)
					(thickness 0.15)
				)
				(justify left bottom)
				(hide yes)
			)
		)
		(property "Author" "Antmicro"
			(at 139.7 161.29 0)
			(effects
				(font
					(size 1.27 1.27)
					(thickness 0.15)
				)
				(justify left bottom)
				(hide yes)
			)
		)
		(property "Tolerance" "1%"
			(at 139.7 179.07 0)
			(effects
				(font
					(size 1.27 1.27)
				)
				(justify left bottom)
				(hide yes)
			)
		)
		(pin "1"
		)
		(pin "2"
		)
		(instances
			(project "jetson-agx-thor-baseboard"
				(path ""
					(reference "R280")
					(unit 1)
				)
			)
		)
	)
	(symbol
		(lib_id "antmicropower:+5V")
		(at 162.56 97.79 0)
		(unit 1)
		(exclude_from_sim no)
		(in_bom yes)
		(on_board yes)
		(dnp no)
		(property "Reference" "#PWR0456"
			(at 162.56 101.6 0)
			(effects
				(font
					(size 1.27 1.27)
				)
				(justify left bottom)
				(hide yes)
			)
		)
		(property "Value" "+5V"
			(at 162.56 93.98 0)
			(effects
				(font
					(size 1.27 1.27)
					(thickness 0.15)
				)
			)
		)
		(property "Footprint" ""
			(at 177.8 105.41 0)
			(effects
				(font
					(size 1.27 1.27)
					(thickness 0.15)
				)
				(justify left bottom)
				(hide yes)
			)
		)
		(property "Datasheet" ""
			(at 177.8 107.95 0)
			(effects
				(font
					(size 1.27 1.27)
					(thickness 0.15)
				)
				(justify left bottom)
				(hide yes)
			)
		)
		(property "Description" ""
			(at 162.56 97.79 0)
			(effects
				(font
					(size 1.27 1.27)
				)
				(hide yes)
			)
		)
		(property "Author" "Antmicro"
			(at 177.8 105.41 0)
			(effects
				(font
					(size 1.27 1.27)
					(thickness 0.15)
				)
				(justify left bottom)
				(hide yes)
			)
		)
		(property "License" "Apache-2.0"
			(at 177.8 107.95 0)
			(effects
				(font
					(size 1.27 1.27)
					(thickness 0.15)
				)
				(justify left bottom)
				(hide yes)
			)
		)
		(pin "1"
		)
		(instances
			(project "jetson-agx-thor-baseboard"
				(path ""
					(reference "#PWR0456")
					(unit 1)
				)
			)
		)
	)
	(symbol
		(lib_id "antmicroTVSDiodes:TPD4E05U06QDQARQ1")
		(at 288.29 182.88 270)
		(unit 1)
		(exclude_from_sim no)
		(in_bom yes)
		(on_board yes)
		(dnp no)
		(property "Reference" "U57"
			(at 283.845 193.04 90)
			(effects
				(font
					(size 1.27 1.27)
				)
			)
		)
		(property "Value" "TPD4E05U06QDQARQ1"
			(at 278.13 207.01 0)
			(effects
				(font
					(size 1.27 1.27)
					(thickness 0.15)
				)
				(justify left bottom)
				(hide yes)
			)
		)
		(property "Footprint" "antmicro-footprints:USON-10_2.5x1mm_P0.5mm"
			(at 283.21 207.01 0)
			(effects
				(font
					(size 1.27 1.27)
					(thickness 0.15)
				)
				(justify left bottom)
				(hide yes)
			)
		)
		(property "Datasheet" "https://www.ti.com/lit/ds/symlink/tpd4e05u06-q1.pdf?HQS=dis-mous-null-mousermode-dsf-pf-null-wwe&ts=1663591265741&ref_url=https%253A%252F%252Fwww.mouser.com%252F"
			(at 280.67 207.01 0)
			(effects
				(font
					(size 1.27 1.27)
					(thickness 0.15)
				)
				(justify left bottom)
				(hide yes)
			)
		)
		(property "Description" "TVS diode array, 12 kV, USON-10, 5.5 V, 0.5 pF"
			(at 288.29 182.88 0)
			(effects
				(font
					(size 1.27 1.27)
				)
				(hide yes)
			)
		)
		(property "Manufacturer" "Texas Instruments"
			(at 275.59 207.01 0)
			(effects
				(font
					(size 1.27 1.27)
					(thickness 0.15)
				)
				(justify left bottom)
				(hide yes)
			)
		)
		(property "MPN" "TPD4E05U06QDQARQ1"
			(at 283.845 195.58 90)
			(effects
				(font
					(size 1.27 1.27)
					(thickness 0.15)
				)
			)
		)
		(property "Author" "Antmicro"
			(at 273.05 207.01 0)
			(effects
				(font
					(size 1.27 1.27)
					(thickness 0.15)
				)
				(justify left bottom)
				(hide yes)
			)
		)
		(property "License" "Apache-2.0"
			(at 270.51 207.01 0)
			(effects
				(font
					(size 1.27 1.27)
					(thickness 0.15)
				)
				(justify left bottom)
				(hide yes)
			)
		)
		(pin "1"
		)
		(pin "10"
		)
		(pin "2"
		)
		(pin "3"
		)
		(pin "4"
		)
		(pin "5"
		)
		(pin "6"
		)
		(pin "7"
		)
		(pin "8"
		)
		(pin "9"
		)
		(instances
			(project "jetson-agx-thor-baseboard"
				(path ""
					(reference "U57")
					(unit 1)
				)
			)
		)
	)
	(symbol
		(lib_id "antmicroResistors0402:R_10k_0402")
		(at 231.14 90.17 180)
		(unit 1)
		(exclude_from_sim no)
		(in_bom yes)
		(on_board yes)
		(dnp no)
		(property "Reference" "R269"
			(at 236.22 88.265 0)
			(effects
				(font
					(size 1.27 1.27)
				)
				(justify left bottom)
			)
		)
		(property "Value" "R_10k_0402"
			(at 210.82 77.47 0)
			(effects
				(font
					(size 1.27 1.27)
					(thickness 0.15)
				)
				(justify left bottom)
				(hide yes)
			)
		)
		(property "Footprint" "antmicro-footprints:R_0402_1005Metric"
			(at 210.82 74.93 0)
			(effects
				(font
					(size 1.27 1.27)
					(thickness 0.15)
				)
				(justify left bottom)
				(hide yes)
			)
		)
		(property "Datasheet" "https://www.bourns.com/docs/product-datasheets/cr.pdf"
			(at 210.82 72.39 0)
			(effects
				(font
					(size 1.27 1.27)
					(thickness 0.15)
				)
				(justify left bottom)
				(hide yes)
			)
		)
		(property "Description" "SMD Chip Resistor, 10 kohm, ± 1%, 62.5 mW, 0402 [1005 Metric], Thick Film, General Purpose"
			(at 231.14 90.17 0)
			(effects
				(font
					(size 1.27 1.27)
				)
				(hide yes)
			)
		)
		(property "Manufacturer" "Bourns"
			(at 210.82 67.31 0)
			(effects
				(font
					(size 1.27 1.27)
					(thickness 0.15)
				)
				(justify left bottom)
				(hide yes)
			)
		)
		(property "MPN" "CR0402-FX-1002GLF"
			(at 210.82 69.85 0)
			(effects
				(font
					(size 1.27 1.27)
					(thickness 0.15)
				)
				(justify left bottom)
				(hide yes)
			)
		)
		(property "Val" "10k"
			(at 226.06 88.265 0)
			(effects
				(font
					(size 1.27 1.27)
					(thickness 0.15)
				)
				(justify left bottom)
			)
		)
		(property "License" "Apache-2.0"
			(at 210.82 64.77 0)
			(effects
				(font
					(size 1.27 1.27)
					(thickness 0.15)
				)
				(justify left bottom)
				(hide yes)
			)
		)
		(property "Author" "Antmicro"
			(at 210.82 62.23 0)
			(effects
				(font
					(size 1.27 1.27)
					(thickness 0.15)
				)
				(justify left bottom)
				(hide yes)
			)
		)
		(property "Tolerance" "1%"
			(at 210.82 80.01 0)
			(effects
				(font
					(size 1.27 1.27)
				)
				(justify left bottom)
				(hide yes)
			)
		)
		(pin "1"
		)
		(pin "2"
		)
		(instances
			(project "jetson-agx-thor-baseboard"
				(path ""
					(reference "R269")
					(unit 1)
				)
			)
		)
	)
	(symbol
		(lib_id "antmicroLEDIndicationDiscrete:LED_G_0603_LTST-C190GKT")
		(at 321.31 97.79 90)
		(unit 1)
		(exclude_from_sim no)
		(in_bom yes)
		(on_board yes)
		(dnp no)
		(fields_autoplaced yes)
		(property "Reference" "D51"
			(at 323.215 93.98 90)
			(effects
				(font
					(size 1.27 1.27)
				)
				(justify right)
			)
		)
		(property "Value" "LED_G_0603_LTST-C190GKT"
			(at 328.93 74.93 0)
			(effects
				(font
					(size 1.27 1.27)
					(thickness 0.15)
				)
				(justify left bottom)
				(hide yes)
			)
		)
		(property "Footprint" "antmicro-footprints:LED_0603_1608Metric_G"
			(at 331.47 74.93 0)
			(effects
				(font
					(size 1.27 1.27)
					(thickness 0.15)
				)
				(justify left bottom)
				(hide yes)
			)
		)
		(property "Datasheet" "https://media.digikey.com/pdf/Data%20Sheets/Lite-On%20PDFs/LTST-C190GKT.pdf"
			(at 334.01 74.93 0)
			(effects
				(font
					(size 1.27 1.27)
					(thickness 0.15)
				)
				(justify left bottom)
				(hide yes)
			)
		)
		(property "Description" "LED, Green, SMD, 0603, 20 mA, 2.1 V, 569 nm"
			(at 321.31 97.79 0)
			(effects
				(font
					(size 1.27 1.27)
				)
				(hide yes)
			)
		)
		(property "MPN" "LTST-C190GKT"
			(at 336.55 74.93 0)
			(effects
				(font
					(size 1.27 1.27)
					(thickness 0.15)
				)
				(justify left bottom)
				(hide yes)
			)
		)
		(property "Manufacturer" "Lite-On"
			(at 339.09 74.93 0)
			(effects
				(font
					(size 1.27 1.27)
					(thickness 0.15)
				)
				(justify left bottom)
				(hide yes)
			)
		)
		(property "Author" "Antmicro"
			(at 341.63 74.93 0)
			(effects
				(font
					(size 1.27 1.27)
					(thickness 0.15)
				)
				(justify left bottom)
				(hide yes)
			)
		)
		(property "License" "Apache-2.0"
			(at 344.17 74.93 0)
			(effects
				(font
					(size 1.27 1.27)
					(thickness 0.15)
				)
				(justify left bottom)
				(hide yes)
			)
		)
		(property "Color" "Green"
			(at 323.215 96.52 90)
			(effects
				(font
					(size 1.27 1.27)
				)
				(justify right)
			)
		)
		(pin "1"
		)
		(pin "2"
		)
		(instances
			(project "jetson-agx-thor-baseboard"
				(path ""
					(reference "D51")
					(unit 1)
				)
			)
		)
	)
	(symbol
		(lib_id "antmicroUSBConnectors:USB-C_Kycon_KUSBX-SL2-CS1N24-B-TR")
		(at 300.99 127 0)
		(mirror y)
		(unit 1)
		(exclude_from_sim no)
		(in_bom yes)
		(on_board yes)
		(dnp no)
		(property "Reference" "J3"
			(at 314.325 119.38 0)
			(effects
				(font
					(size 1.27 1.27)
					(thickness 0.15)
				)
			)
		)
		(property "Value" "USB-C_Kycon_KUSBX-SL2-CS1N24-B-TR"
			(at 257.81 132.08 0)
			(effects
				(font
					(size 1.27 1.27)
					(thickness 0.15)
				)
				(justify left bottom)
				(hide yes)
			)
		)
		(property "Footprint" "antmicro-footprints:USB-C_Receptacle_Kycon_KUSBX-SL2-CS1N24-B-TR"
			(at 257.81 134.62 0)
			(effects
				(font
					(size 1.27 1.27)
					(thickness 0.15)
				)
				(justify left bottom)
				(hide yes)
			)
		)
		(property "Datasheet" "https://www.kycon.com/Pub_Eng_Draw/KUSBX-SL2-CS1N24-B-TR.pdf"
			(at 257.81 137.16 0)
			(effects
				(font
					(size 1.27 1.27)
					(thickness 0.15)
				)
				(justify left bottom)
				(hide yes)
			)
		)
		(property "Description" "USB-C (USB TYPE-C) USB 3.2 Gen 2 (USB 3.1 Gen 2, Superspeed + (USB 3.1)) USB PD Receptacle Connector 24 Position Surface Mount"
			(at 257.81 149.86 0)
			(effects
				(font
					(size 1.27 1.27)
				)
				(justify left bottom)
				(hide yes)
			)
		)
		(property "MPN" "KUSBX-SL2-CS1N24-B-TR"
			(at 314.325 121.92 0)
			(effects
				(font
					(size 1.27 1.27)
					(thickness 0.15)
				)
			)
		)
		(property "Manufacturer" "Kycon"
			(at 257.81 142.24 0)
			(effects
				(font
					(size 1.27 1.27)
					(thickness 0.15)
				)
				(justify left bottom)
				(hide yes)
			)
		)
		(property "License" "Apache-2.0"
			(at 257.81 144.78 0)
			(effects
				(font
					(size 1.27 1.27)
					(thickness 0.15)
				)
				(justify left bottom)
				(hide yes)
			)
		)
		(property "Author" "Antmicro"
			(at 257.81 147.32 0)
			(effects
				(font
					(size 1.27 1.27)
					(thickness 0.15)
				)
				(justify left bottom)
				(hide yes)
			)
		)
		(pin "A6"
		)
		(pin "A2"
		)
		(pin "SH"
		)
		(pin "A1"
		)
		(pin "B12"
		)
		(pin "B7"
		)
		(pin "A12"
		)
		(pin "A8"
		)
		(pin "B1"
		)
		(pin "B8"
		)
		(pin "A3"
		)
		(pin "B10"
		)
		(pin "B3"
		)
		(pin "A7"
		)
		(pin "A11"
		)
		(pin "B5"
		)
		(pin "B9"
		)
		(pin "A5"
		)
		(pin "A9"
		)
		(pin "B4"
		)
		(pin "A4"
		)
		(pin "B6"
		)
		(pin "B2"
		)
		(pin "B11"
		)
		(pin "A10"
		)
		(instances
			(project "jetson-agx-thor-baseboard"
				(path ""
					(reference "J3")
					(unit 1)
				)
			)
		)
	)
	(symbol
		(lib_id "antmicropower:+5V")
		(at 209.55 105.41 0)
		(mirror y)
		(unit 1)
		(exclude_from_sim no)
		(in_bom yes)
		(on_board yes)
		(dnp no)
		(property "Reference" "#PWR0462"
			(at 209.55 109.22 0)
			(effects
				(font
					(size 1.27 1.27)
				)
				(justify left bottom)
				(hide yes)
			)
		)
		(property "Value" "+5V"
			(at 207.01 101.6 0)
			(effects
				(font
					(size 1.27 1.27)
					(thickness 0.15)
				)
				(justify right)
			)
		)
		(property "Footprint" ""
			(at 194.31 113.03 0)
			(effects
				(font
					(size 1.27 1.27)
					(thickness 0.15)
				)
				(justify left bottom)
				(hide yes)
			)
		)
		(property "Datasheet" ""
			(at 194.31 115.57 0)
			(effects
				(font
					(size 1.27 1.27)
					(thickness 0.15)
				)
				(justify left bottom)
				(hide yes)
			)
		)
		(property "Description" ""
			(at 209.55 105.41 0)
			(effects
				(font
					(size 1.27 1.27)
				)
				(hide yes)
			)
		)
		(property "Author" "Antmicro"
			(at 194.31 113.03 0)
			(effects
				(font
					(size 1.27 1.27)
					(thickness 0.15)
				)
				(justify left bottom)
				(hide yes)
			)
		)
		(property "License" "Apache-2.0"
			(at 194.31 115.57 0)
			(effects
				(font
					(size 1.27 1.27)
					(thickness 0.15)
				)
				(justify left bottom)
				(hide yes)
			)
		)
		(pin "1"
		)
		(instances
			(project "jetson-agx-thor-baseboard"
				(path ""
					(reference "#PWR0462")
					(unit 1)
				)
			)
		)
	)
	(symbol
		(lib_id "antmicroResistors0402:R_10k_0402")
		(at 133.35 129.54 90)
		(unit 1)
		(exclude_from_sim no)
		(in_bom yes)
		(on_board yes)
		(dnp no)
		(property "Reference" "R278"
			(at 134.62 125.73 90)
			(effects
				(font
					(size 1.27 1.27)
				)
				(justify right)
			)
		)
		(property "Value" "R_10k_0402"
			(at 146.05 109.22 0)
			(effects
				(font
					(size 1.27 1.27)
					(thickness 0.15)
				)
				(justify left bottom)
				(hide yes)
			)
		)
		(property "Footprint" "antmicro-footprints:R_0402_1005Metric"
			(at 148.59 109.22 0)
			(effects
				(font
					(size 1.27 1.27)
					(thickness 0.15)
				)
				(justify left bottom)
				(hide yes)
			)
		)
		(property "Datasheet" "https://www.bourns.com/docs/product-datasheets/cr.pdf"
			(at 151.13 109.22 0)
			(effects
				(font
					(size 1.27 1.27)
					(thickness 0.15)
				)
				(justify left bottom)
				(hide yes)
			)
		)
		(property "Description" "SMD Chip Resistor, 10 kohm, ± 1%, 62.5 mW, 0402 [1005 Metric], Thick Film, General Purpose"
			(at 133.35 129.54 0)
			(effects
				(font
					(size 1.27 1.27)
				)
				(hide yes)
			)
		)
		(property "Manufacturer" "Bourns"
			(at 156.21 109.22 0)
			(effects
				(font
					(size 1.27 1.27)
					(thickness 0.15)
				)
				(justify left bottom)
				(hide yes)
			)
		)
		(property "MPN" "CR0402-FX-1002GLF"
			(at 153.67 109.22 0)
			(effects
				(font
					(size 1.27 1.27)
					(thickness 0.15)
				)
				(justify left bottom)
				(hide yes)
			)
		)
		(property "Val" "10k"
			(at 134.62 128.27 90)
			(effects
				(font
					(size 1.27 1.27)
					(thickness 0.15)
				)
				(justify right)
			)
		)
		(property "License" "Apache-2.0"
			(at 158.75 109.22 0)
			(effects
				(font
					(size 1.27 1.27)
					(thickness 0.15)
				)
				(justify left bottom)
				(hide yes)
			)
		)
		(property "Author" "Antmicro"
			(at 161.29 109.22 0)
			(effects
				(font
					(size 1.27 1.27)
					(thickness 0.15)
				)
				(justify left bottom)
				(hide yes)
			)
		)
		(property "Tolerance" "1%"
			(at 143.51 109.22 0)
			(effects
				(font
					(size 1.27 1.27)
				)
				(justify left bottom)
				(hide yes)
			)
		)
		(pin "1"
		)
		(pin "2"
		)
		(instances
			(project "jetson-agx-thor-baseboard"
				(path ""
					(reference "R278")
					(unit 1)
				)
			)
		)
	)
	(symbol
		(lib_id "antmicropower:GND")
		(at 140.97 106.68 0)
		(unit 1)
		(exclude_from_sim no)
		(in_bom yes)
		(on_board yes)
		(dnp no)
		(property "Reference" "#PWR0459"
			(at 140.97 113.03 0)
			(effects
				(font
					(size 1.27 1.27)
				)
				(justify left bottom)
				(hide yes)
			)
		)
		(property "Value" "GND"
			(at 140.97 110.49 0)
			(effects
				(font
					(size 1.27 1.27)
					(thickness 0.15)
				)
			)
		)
		(property "Footprint" ""
			(at 149.86 114.3 0)
			(effects
				(font
					(size 1.27 1.27)
					(thickness 0.15)
				)
				(justify left bottom)
				(hide yes)
			)
		)
		(property "Datasheet" ""
			(at 149.86 119.38 0)
			(effects
				(font
					(size 1.27 1.27)
					(thickness 0.15)
				)
				(justify left bottom)
				(hide yes)
			)
		)
		(property "Description" ""
			(at 140.97 106.68 0)
			(effects
				(font
					(size 1.27 1.27)
				)
				(hide yes)
			)
		)
		(property "Author" "Antmicro"
			(at 149.86 114.3 0)
			(effects
				(font
					(size 1.27 1.27)
					(thickness 0.15)
				)
				(justify left bottom)
				(hide yes)
			)
		)
		(property "License" "Apache-2.0"
			(at 149.86 116.84 0)
			(effects
				(font
					(size 1.27 1.27)
					(thickness 0.15)
				)
				(justify left bottom)
				(hide yes)
			)
		)
		(pin "1"
		)
		(instances
			(project "jetson-agx-thor-baseboard"
				(path ""
					(reference "#PWR0459")
					(unit 1)
				)
			)
		)
	)
	(symbol
		(lib_id "antmicroResistors0402:R_10k_0402")
		(at 217.17 106.68 270)
		(unit 1)
		(exclude_from_sim no)
		(in_bom yes)
		(on_board yes)
		(dnp no)
		(property "Reference" "R266"
			(at 218.44 107.95 90)
			(effects
				(font
					(size 1.27 1.27)
				)
				(justify left)
			)
		)
		(property "Value" "R_10k_0402"
			(at 204.47 127 0)
			(effects
				(font
					(size 1.27 1.27)
					(thickness 0.15)
				)
				(justify left bottom)
				(hide yes)
			)
		)
		(property "Footprint" "antmicro-footprints:R_0402_1005Metric"
			(at 201.93 127 0)
			(effects
				(font
					(size 1.27 1.27)
					(thickness 0.15)
				)
				(justify left bottom)
				(hide yes)
			)
		)
		(property "Datasheet" "https://www.bourns.com/docs/product-datasheets/cr.pdf"
			(at 199.39 127 0)
			(effects
				(font
					(size 1.27 1.27)
					(thickness 0.15)
				)
				(justify left bottom)
				(hide yes)
			)
		)
		(property "Description" "SMD Chip Resistor, 10 kohm, ± 1%, 62.5 mW, 0402 [1005 Metric], Thick Film, General Purpose"
			(at 217.17 106.68 0)
			(effects
				(font
					(size 1.27 1.27)
				)
				(hide yes)
			)
		)
		(property "Manufacturer" "Bourns"
			(at 194.31 127 0)
			(effects
				(font
					(size 1.27 1.27)
					(thickness 0.15)
				)
				(justify left bottom)
				(hide yes)
			)
		)
		(property "MPN" "CR0402-FX-1002GLF"
			(at 196.85 127 0)
			(effects
				(font
					(size 1.27 1.27)
					(thickness 0.15)
				)
				(justify left bottom)
				(hide yes)
			)
		)
		(property "Val" "10k"
			(at 218.44 110.49 90)
			(effects
				(font
					(size 1.27 1.27)
					(thickness 0.15)
				)
				(justify left)
			)
		)
		(property "License" "Apache-2.0"
			(at 191.77 127 0)
			(effects
				(font
					(size 1.27 1.27)
					(thickness 0.15)
				)
				(justify left bottom)
				(hide yes)
			)
		)
		(property "Author" "Antmicro"
			(at 189.23 127 0)
			(effects
				(font
					(size 1.27 1.27)
					(thickness 0.15)
				)
				(justify left bottom)
				(hide yes)
			)
		)
		(property "Tolerance" "1%"
			(at 207.01 127 0)
			(effects
				(font
					(size 1.27 1.27)
				)
				(justify left bottom)
				(hide yes)
			)
		)
		(pin "1"
		)
		(pin "2"
		)
		(instances
			(project "jetson-agx-thor-baseboard"
				(path ""
					(reference "R266")
					(unit 1)
				)
			)
		)
	)
	(symbol
		(lib_id "antmicroResistors0402:R_0R_0402")
		(at 240.03 87.63 0)
		(unit 1)
		(exclude_from_sim no)
		(in_bom yes)
		(on_board yes)
		(dnp no)
		(property "Reference" "R268"
			(at 242.316 85.598 0)
			(effects
				(font
					(size 1.27 1.27)
					(thickness 0.15)
				)
			)
		)
		(property "Value" "R_0R_0402"
			(at 260.35 100.33 0)
			(effects
				(font
					(size 1.27 1.27)
					(thickness 0.15)
				)
				(justify left bottom)
				(hide yes)
			)
		)
		(property "Footprint" "antmicro-footprints:R_0402_1005Metric"
			(at 260.35 102.87 0)
			(effects
				(font
					(size 1.27 1.27)
					(thickness 0.15)
				)
				(justify left bottom)
				(hide yes)
			)
		)
		(property "Datasheet" "https://industrial.panasonic.com/cdbs/www-data/pdf/RDA0000/AOA0000C301.pdf"
			(at 260.35 105.41 0)
			(effects
				(font
					(size 1.27 1.27)
					(thickness 0.15)
				)
				(justify left bottom)
				(hide yes)
			)
		)
		(property "Description" "SMD Chip Resistor, Jumper, 0 ohm, 100 mW, 0402 [1005 Metric], Thick Film, General Purpose"
			(at 260.35 120.65 0)
			(effects
				(font
					(size 1.27 1.27)
				)
				(justify left bottom)
				(hide yes)
			)
		)
		(property "MPN" "ERJ2GE0R00X"
			(at 260.35 107.95 0)
			(effects
				(font
					(size 1.27 1.27)
					(thickness 0.15)
				)
				(justify left bottom)
				(hide yes)
			)
		)
		(property "Manufacturer" "Panasonic"
			(at 260.35 110.49 0)
			(effects
				(font
					(size 1.27 1.27)
					(thickness 0.15)
				)
				(justify left bottom)
				(hide yes)
			)
		)
		(property "License" "Apache-2.0"
			(at 260.35 113.03 0)
			(effects
				(font
					(size 1.27 1.27)
					(thickness 0.15)
				)
				(justify left bottom)
				(hide yes)
			)
		)
		(property "Author" "Antmicro"
			(at 260.35 115.57 0)
			(effects
				(font
					(size 1.27 1.27)
					(thickness 0.15)
				)
				(justify left bottom)
				(hide yes)
			)
		)
		(property "Val" "0R"
			(at 242.57 87.63 0)
			(effects
				(font
					(size 1.27 1.27)
					(thickness 0.15)
				)
			)
		)
		(property "Tolerance" "~"
			(at 260.35 97.79 0)
			(effects
				(font
					(size 1.27 1.27)
				)
				(justify left bottom)
				(hide yes)
			)
		)
		(property "Current" "1A"
			(at 260.35 118.11 0)
			(effects
				(font
					(size 1.27 1.27)
					(thickness 0.15)
				)
				(justify left bottom)
				(hide yes)
			)
		)
		(pin "2"
		)
		(pin "1"
		)
		(instances
			(project ""
				(path ""
					(reference "R268")
					(unit 1)
				)
			)
		)
	)
	(symbol
		(lib_id "antmicroCapacitors0402:C_100n_0402")
		(at 132.08 154.94 0)
		(mirror x)
		(unit 1)
		(exclude_from_sim no)
		(in_bom yes)
		(on_board yes)
		(dnp no)
		(property "Reference" "C201"
			(at 138.43 153.67 0)
			(effects
				(font
					(size 1.27 1.27)
				)
			)
		)
		(property "Value" "C_100n_0402"
			(at 152.4 144.78 0)
			(effects
				(font
					(size 1.27 1.27)
					(thickness 0.15)
				)
				(justify left bottom)
				(hide yes)
			)
		)
		(property "Footprint" "antmicro-footprints:C_0402_1005Metric"
			(at 152.4 142.24 0)
			(effects
				(font
					(size 1.27 1.27)
					(thickness 0.15)
				)
				(justify left bottom)
				(hide yes)
			)
		)
		(property "Datasheet" "https://www.murata.com/products/productdetail?partno=GRM155R61H104KE14%23"
			(at 152.4 139.7 0)
			(effects
				(font
					(size 1.27 1.27)
					(thickness 0.15)
				)
				(justify left bottom)
				(hide yes)
			)
		)
		(property "Description" "SMD Multilayer Ceramic Capacitor, 0.1 µF, 50 V, 0402 [1005 Metric], ± 10%, X5R, GRM Series"
			(at 132.08 154.94 0)
			(effects
				(font
					(size 1.27 1.27)
				)
				(hide yes)
			)
		)
		(property "Manufacturer" "Murata"
			(at 152.4 134.62 0)
			(effects
				(font
					(size 1.27 1.27)
					(thickness 0.15)
				)
				(justify left bottom)
				(hide yes)
			)
		)
		(property "MPN" "GRM155R61H104KE14D"
			(at 152.4 137.16 0)
			(effects
				(font
					(size 1.27 1.27)
					(thickness 0.15)
				)
				(justify left bottom)
				(hide yes)
			)
		)
		(property "Val" "100n"
			(at 130.81 156.21 0)
			(effects
				(font
					(size 1.27 1.27)
					(thickness 0.15)
				)
			)
		)
		(property "License" "Apache-2.0"
			(at 152.4 132.08 0)
			(effects
				(font
					(size 1.27 1.27)
					(thickness 0.15)
				)
				(justify left bottom)
				(hide yes)
			)
		)
		(property "Author" "Antmicro"
			(at 152.4 129.54 0)
			(effects
				(font
					(size 1.27 1.27)
					(thickness 0.15)
				)
				(justify left bottom)
				(hide yes)
			)
		)
		(property "Voltage" "50V"
			(at 152.4 127 0)
			(effects
				(font
					(size 1.27 1.27)
				)
				(justify left bottom)
				(hide yes)
			)
		)
		(property "Dielectric" "X5R"
			(at 152.4 124.46 0)
			(effects
				(font
					(size 1.27 1.27)
				)
				(justify left bottom)
				(hide yes)
			)
		)
		(pin "1"
		)
		(pin "2"
		)
		(instances
			(project "jetson-agx-thor-baseboard"
				(path ""
					(reference "C201")
					(unit 1)
				)
			)
		)
	)
	(symbol
		(lib_id "antmicropower:+5V")
		(at 124.46 120.65 0)
		(unit 1)
		(exclude_from_sim no)
		(in_bom yes)
		(on_board yes)
		(dnp no)
		(property "Reference" "#PWR0455"
			(at 124.46 124.46 0)
			(effects
				(font
					(size 1.27 1.27)
				)
				(justify left bottom)
				(hide yes)
			)
		)
		(property "Value" "+5V"
			(at 121.92 116.84 0)
			(effects
				(font
					(size 1.27 1.27)
					(thickness 0.15)
				)
				(justify left)
			)
		)
		(property "Footprint" ""
			(at 139.7 128.27 0)
			(effects
				(font
					(size 1.27 1.27)
					(thickness 0.15)
				)
				(justify left bottom)
				(hide yes)
			)
		)
		(property "Datasheet" ""
			(at 139.7 130.81 0)
			(effects
				(font
					(size 1.27 1.27)
					(thickness 0.15)
				)
				(justify left bottom)
				(hide yes)
			)
		)
		(property "Description" ""
			(at 124.46 120.65 0)
			(effects
				(font
					(size 1.27 1.27)
				)
				(hide yes)
			)
		)
		(property "Author" "Antmicro"
			(at 139.7 128.27 0)
			(effects
				(font
					(size 1.27 1.27)
					(thickness 0.15)
				)
				(justify left bottom)
				(hide yes)
			)
		)
		(property "License" "Apache-2.0"
			(at 139.7 130.81 0)
			(effects
				(font
					(size 1.27 1.27)
					(thickness 0.15)
				)
				(justify left bottom)
				(hide yes)
			)
		)
		(pin "1"
		)
		(instances
			(project "jetson-agx-thor-baseboard"
				(path ""
					(reference "#PWR0455")
					(unit 1)
				)
			)
		)
	)
	(symbol
		(lib_id "antmicroCapacitorsmisc:C_22u_25V_0805")
		(at 279.4 86.36 90)
		(mirror x)
		(unit 1)
		(exclude_from_sim no)
		(in_bom yes)
		(on_board yes)
		(dnp no)
		(fields_autoplaced yes)
		(property "Reference" "C115"
			(at 281.94 87.6363 90)
			(effects
				(font
					(size 1.27 1.27)
				)
				(justify right)
			)
		)
		(property "Value" "C_22u_25V_0805"
			(at 289.56 106.68 0)
			(effects
				(font
					(size 1.27 1.27)
					(thickness 0.15)
				)
				(justify left bottom)
				(hide yes)
			)
		)
		(property "Footprint" "antmicro-footprints:C_0805_2012Metric"
			(at 292.1 106.68 0)
			(effects
				(font
					(size 1.27 1.27)
					(thickness 0.15)
				)
				(justify left bottom)
				(hide yes)
			)
		)
		(property "Datasheet" "https://product.samsungsem.com/mlcc/CL21A226MAYNNN.do"
			(at 294.64 106.68 0)
			(effects
				(font
					(size 1.27 1.27)
					(thickness 0.15)
				)
				(justify left bottom)
				(hide yes)
			)
		)
		(property "Description" "SMT Multilayer Ceramic Capacitor, 22uF, +/-20%, 25V, X5R, 0805 [2012 Metric]"
			(at 279.4 86.36 0)
			(effects
				(font
					(size 1.27 1.27)
				)
				(hide yes)
			)
		)
		(property "Manufacturer" "Samsung Electro-Mechanics"
			(at 299.72 106.68 0)
			(effects
				(font
					(size 1.27 1.27)
					(thickness 0.15)
				)
				(justify left bottom)
				(hide yes)
			)
		)
		(property "MPN" "CL21A226MAYNNNE"
			(at 297.18 106.68 0)
			(effects
				(font
					(size 1.27 1.27)
					(thickness 0.15)
				)
				(justify left bottom)
				(hide yes)
			)
		)
		(property "Val" "22u"
			(at 281.94 90.1763 90)
			(effects
				(font
					(size 1.27 1.27)
					(thickness 0.15)
				)
				(justify right)
			)
		)
		(property "License" "Apache-2.0"
			(at 302.26 106.68 0)
			(effects
				(font
					(size 1.27 1.27)
					(thickness 0.15)
				)
				(justify left bottom)
				(hide yes)
			)
		)
		(property "Author" "Antmicro"
			(at 304.8 106.68 0)
			(effects
				(font
					(size 1.27 1.27)
					(thickness 0.15)
				)
				(justify left bottom)
				(hide yes)
			)
		)
		(property "Voltage" "25V"
			(at 307.34 106.68 0)
			(effects
				(font
					(size 1.27 1.27)
				)
				(justify left bottom)
				(hide yes)
			)
		)
		(property "Dielectric" "X5R"
			(at 309.88 106.68 0)
			(effects
				(font
					(size 1.27 1.27)
				)
				(justify left bottom)
				(hide yes)
			)
		)
		(property "Public" "False"
			(at 312.42 106.68 0)
			(effects
				(font
					(size 1.27 1.27)
				)
				(justify left bottom)
				(hide yes)
			)
		)
		(pin "1"
		)
		(pin "2"
		)
		(instances
			(project "jetson-agx-thor-baseboard"
				(path ""
					(reference "C115")
					(unit 1)
				)
			)
		)
	)
	(symbol
		(lib_id "antmicropower:GND")
		(at 153.67 106.68 0)
		(unit 1)
		(exclude_from_sim no)
		(in_bom yes)
		(on_board yes)
		(dnp no)
		(property "Reference" "#PWR0483"
			(at 153.67 113.03 0)
			(effects
				(font
					(size 1.27 1.27)
				)
				(justify left bottom)
				(hide yes)
			)
		)
		(property "Value" "GND"
			(at 153.67 110.49 0)
			(effects
				(font
					(size 1.27 1.27)
					(thickness 0.15)
				)
			)
		)
		(property "Footprint" ""
			(at 162.56 114.3 0)
			(effects
				(font
					(size 1.27 1.27)
					(thickness 0.15)
				)
				(justify left bottom)
				(hide yes)
			)
		)
		(property "Datasheet" ""
			(at 162.56 119.38 0)
			(effects
				(font
					(size 1.27 1.27)
					(thickness 0.15)
				)
				(justify left bottom)
				(hide yes)
			)
		)
		(property "Description" ""
			(at 153.67 106.68 0)
			(effects
				(font
					(size 1.27 1.27)
				)
				(hide yes)
			)
		)
		(property "Author" "Antmicro"
			(at 162.56 114.3 0)
			(effects
				(font
					(size 1.27 1.27)
					(thickness 0.15)
				)
				(justify left bottom)
				(hide yes)
			)
		)
		(property "License" "Apache-2.0"
			(at 162.56 116.84 0)
			(effects
				(font
					(size 1.27 1.27)
					(thickness 0.15)
				)
				(justify left bottom)
				(hide yes)
			)
		)
		(pin "1"
		)
		(instances
			(project "jetson-agx-thor-baseboard"
				(path ""
					(reference "#PWR0483")
					(unit 1)
				)
			)
		)
	)
	(symbol
		(lib_id "antmicropower:GND")
		(at 279.4 120.65 0)
		(unit 1)
		(exclude_from_sim no)
		(in_bom yes)
		(on_board yes)
		(dnp no)
		(property "Reference" "#PWR0476"
			(at 279.4 127 0)
			(effects
				(font
					(size 1.27 1.27)
				)
				(justify left bottom)
				(hide yes)
			)
		)
		(property "Value" "GND"
			(at 279.4 124.46 0)
			(effects
				(font
					(size 1.27 1.27)
					(thickness 0.15)
				)
			)
		)
		(property "Footprint" ""
			(at 288.29 128.27 0)
			(effects
				(font
					(size 1.27 1.27)
					(thickness 0.15)
				)
				(justify left bottom)
				(hide yes)
			)
		)
		(property "Datasheet" ""
			(at 288.29 133.35 0)
			(effects
				(font
					(size 1.27 1.27)
					(thickness 0.15)
				)
				(justify left bottom)
				(hide yes)
			)
		)
		(property "Description" ""
			(at 279.4 120.65 0)
			(effects
				(font
					(size 1.27 1.27)
				)
				(hide yes)
			)
		)
		(property "Author" "Antmicro"
			(at 288.29 128.27 0)
			(effects
				(font
					(size 1.27 1.27)
					(thickness 0.15)
				)
				(justify left bottom)
				(hide yes)
			)
		)
		(property "License" "Apache-2.0"
			(at 288.29 130.81 0)
			(effects
				(font
					(size 1.27 1.27)
					(thickness 0.15)
				)
				(justify left bottom)
				(hide yes)
			)
		)
		(pin "1"
		)
		(instances
			(project "jetson-agx-thor-baseboard"
				(path ""
					(reference "#PWR0476")
					(unit 1)
				)
			)
		)
	)
	(symbol
		(lib_id "antmicropower:GND")
		(at 289.56 92.71 0)
		(unit 1)
		(exclude_from_sim no)
		(in_bom yes)
		(on_board yes)
		(dnp no)
		(property "Reference" "#PWR0477"
			(at 289.56 99.06 0)
			(effects
				(font
					(size 1.27 1.27)
				)
				(justify left bottom)
				(hide yes)
			)
		)
		(property "Value" "GND"
			(at 289.56 96.52 0)
			(effects
				(font
					(size 1.27 1.27)
					(thickness 0.15)
				)
			)
		)
		(property "Footprint" ""
			(at 298.45 100.33 0)
			(effects
				(font
					(size 1.27 1.27)
					(thickness 0.15)
				)
				(justify left bottom)
				(hide yes)
			)
		)
		(property "Datasheet" ""
			(at 298.45 105.41 0)
			(effects
				(font
					(size 1.27 1.27)
					(thickness 0.15)
				)
				(justify left bottom)
				(hide yes)
			)
		)
		(property "Description" ""
			(at 289.56 92.71 0)
			(effects
				(font
					(size 1.27 1.27)
				)
				(hide yes)
			)
		)
		(property "Author" "Antmicro"
			(at 298.45 100.33 0)
			(effects
				(font
					(size 1.27 1.27)
					(thickness 0.15)
				)
				(justify left bottom)
				(hide yes)
			)
		)
		(property "License" "Apache-2.0"
			(at 298.45 102.87 0)
			(effects
				(font
					(size 1.27 1.27)
					(thickness 0.15)
				)
				(justify left bottom)
				(hide yes)
			)
		)
		(pin "1"
		)
		(instances
			(project "jetson-agx-thor-baseboard"
				(path ""
					(reference "#PWR0477")
					(unit 1)
				)
			)
		)
	)
	(symbol
		(lib_id "antmicropower:GND")
		(at 299.72 194.31 0)
		(unit 1)
		(exclude_from_sim no)
		(in_bom yes)
		(on_board yes)
		(dnp no)
		(property "Reference" "#PWR0478"
			(at 299.72 200.66 0)
			(effects
				(font
					(size 1.27 1.27)
				)
				(justify left bottom)
				(hide yes)
			)
		)
		(property "Value" "GND"
			(at 299.72 198.12 0)
			(effects
				(font
					(size 1.27 1.27)
					(thickness 0.15)
				)
			)
		)
		(property "Footprint" ""
			(at 308.61 201.93 0)
			(effects
				(font
					(size 1.27 1.27)
					(thickness 0.15)
				)
				(justify left bottom)
				(hide yes)
			)
		)
		(property "Datasheet" ""
			(at 308.61 207.01 0)
			(effects
				(font
					(size 1.27 1.27)
					(thickness 0.15)
				)
				(justify left bottom)
				(hide yes)
			)
		)
		(property "Description" ""
			(at 299.72 194.31 0)
			(effects
				(font
					(size 1.27 1.27)
				)
				(hide yes)
			)
		)
		(property "Author" "Antmicro"
			(at 308.61 201.93 0)
			(effects
				(font
					(size 1.27 1.27)
					(thickness 0.15)
				)
				(justify left bottom)
				(hide yes)
			)
		)
		(property "License" "Apache-2.0"
			(at 308.61 204.47 0)
			(effects
				(font
					(size 1.27 1.27)
					(thickness 0.15)
				)
				(justify left bottom)
				(hide yes)
			)
		)
		(pin "1"
		)
		(instances
			(project "jetson-agx-thor-baseboard"
				(path ""
					(reference "#PWR0478")
					(unit 1)
				)
			)
		)
	)
	(symbol
		(lib_id "antmicroResistors0402:R_2k2_0402")
		(at 265.43 93.98 90)
		(unit 1)
		(exclude_from_sim no)
		(in_bom yes)
		(on_board yes)
		(dnp no)
		(property "Reference" "R270"
			(at 266.7 90.17 90)
			(effects
				(font
					(size 1.27 1.27)
				)
				(justify right)
			)
		)
		(property "Value" "R_2k2_0402"
			(at 278.13 73.66 0)
			(effects
				(font
					(size 1.27 1.27)
					(thickness 0.15)
				)
				(justify left bottom)
				(hide yes)
			)
		)
		(property "Footprint" "antmicro-footprints:R_0402_1005Metric"
			(at 280.67 73.66 0)
			(effects
				(font
					(size 1.27 1.27)
					(thickness 0.15)
				)
				(justify left bottom)
				(hide yes)
			)
		)
		(property "Datasheet" "https://www.bourns.com/docs/product-datasheets/cr.pdf"
			(at 283.21 73.66 0)
			(effects
				(font
					(size 1.27 1.27)
					(thickness 0.15)
				)
				(justify left bottom)
				(hide yes)
			)
		)
		(property "Description" "SMD Chip Resistor, 2.2 kohm, ± 1%, 62.5 mW, 0402 [1005 Metric], Thick Film, General Purpose"
			(at 265.43 93.98 0)
			(effects
				(font
					(size 1.27 1.27)
				)
				(hide yes)
			)
		)
		(property "Manufacturer" "Bourns"
			(at 288.29 73.66 0)
			(effects
				(font
					(size 1.27 1.27)
					(thickness 0.15)
				)
				(justify left bottom)
				(hide yes)
			)
		)
		(property "MPN" "CR0402-FX-2201GLF"
			(at 285.75 73.66 0)
			(effects
				(font
					(size 1.27 1.27)
					(thickness 0.15)
				)
				(justify left bottom)
				(hide yes)
			)
		)
		(property "Val" "2k2"
			(at 266.7 92.71 90)
			(effects
				(font
					(size 1.27 1.27)
					(thickness 0.15)
				)
				(justify right)
			)
		)
		(property "License" "Apache-2.0"
			(at 290.83 73.66 0)
			(effects
				(font
					(size 1.27 1.27)
					(thickness 0.15)
				)
				(justify left bottom)
				(hide yes)
			)
		)
		(property "Author" "Antmicro"
			(at 293.37 73.66 0)
			(effects
				(font
					(size 1.27 1.27)
					(thickness 0.15)
				)
				(justify left bottom)
				(hide yes)
			)
		)
		(property "Tolerance" "1%"
			(at 275.59 73.66 0)
			(effects
				(font
					(size 1.27 1.27)
				)
				(justify left bottom)
				(hide yes)
			)
		)
		(pin "1"
		)
		(pin "2"
		)
		(instances
			(project "jetson-agx-thor-baseboard"
				(path ""
					(reference "R270")
					(unit 1)
				)
			)
		)
	)
	(symbol
		(lib_id "antmicropower:GND")
		(at 245.11 184.15 0)
		(unit 1)
		(exclude_from_sim no)
		(in_bom yes)
		(on_board yes)
		(dnp no)
		(property "Reference" "#PWR0472"
			(at 245.11 190.5 0)
			(effects
				(font
					(size 1.27 1.27)
				)
				(justify left bottom)
				(hide yes)
			)
		)
		(property "Value" "GND"
			(at 245.11 187.96 0)
			(effects
				(font
					(size 1.27 1.27)
					(thickness 0.15)
				)
			)
		)
		(property "Footprint" ""
			(at 254 191.77 0)
			(effects
				(font
					(size 1.27 1.27)
					(thickness 0.15)
				)
				(justify left bottom)
				(hide yes)
			)
		)
		(property "Datasheet" ""
			(at 254 196.85 0)
			(effects
				(font
					(size 1.27 1.27)
					(thickness 0.15)
				)
				(justify left bottom)
				(hide yes)
			)
		)
		(property "Description" ""
			(at 245.11 184.15 0)
			(effects
				(font
					(size 1.27 1.27)
				)
				(hide yes)
			)
		)
		(property "Author" "Antmicro"
			(at 254 191.77 0)
			(effects
				(font
					(size 1.27 1.27)
					(thickness 0.15)
				)
				(justify left bottom)
				(hide yes)
			)
		)
		(property "License" "Apache-2.0"
			(at 254 194.31 0)
			(effects
				(font
					(size 1.27 1.27)
					(thickness 0.15)
				)
				(justify left bottom)
				(hide yes)
			)
		)
		(pin "1"
		)
		(instances
			(project "jetson-agx-thor-baseboard"
				(path ""
					(reference "#PWR0472")
					(unit 1)
				)
			)
		)
	)
	(symbol
		(lib_id "antmicroResistors0402:R_200k_0402")
		(at 119.38 186.69 0)
		(mirror x)
		(unit 1)
		(exclude_from_sim no)
		(in_bom yes)
		(on_board yes)
		(dnp no)
		(property "Reference" "R279"
			(at 114.3 184.785 0)
			(effects
				(font
					(size 1.27 1.27)
				)
				(justify left bottom)
			)
		)
		(property "Value" "R_200k_0402"
			(at 139.7 173.99 0)
			(effects
				(font
					(size 1.27 1.27)
					(thickness 0.15)
				)
				(justify left bottom)
				(hide yes)
			)
		)
		(property "Footprint" "antmicro-footprints:R_0402_1005Metric"
			(at 139.7 171.45 0)
			(effects
				(font
					(size 1.27 1.27)
					(thickness 0.15)
				)
				(justify left bottom)
				(hide yes)
			)
		)
		(property "Datasheet" "https://www.bourns.com/docs/product-datasheets/cr.pdf"
			(at 139.7 168.91 0)
			(effects
				(font
					(size 1.27 1.27)
					(thickness 0.15)
				)
				(justify left bottom)
				(hide yes)
			)
		)
		(property "Description" "SMD Chip Resistor, 200 kohm, ± 1%, 62.5 mW, 0402 [1005 Metric], Thick Film, General Purpose"
			(at 119.38 186.69 0)
			(effects
				(font
					(size 1.27 1.27)
				)
				(hide yes)
			)
		)
		(property "Manufacturer" "Bourns"
			(at 139.7 163.83 0)
			(effects
				(font
					(size 1.27 1.27)
					(thickness 0.15)
				)
				(justify left bottom)
				(hide yes)
			)
		)
		(property "MPN" "CR0402-FX-2003GLF"
			(at 139.7 166.37 0)
			(effects
				(font
					(size 1.27 1.27)
					(thickness 0.15)
				)
				(justify left bottom)
				(hide yes)
			)
		)
		(property "Val" "200k"
			(at 124.46 184.785 0)
			(effects
				(font
					(size 1.27 1.27)
					(thickness 0.15)
				)
				(justify left bottom)
			)
		)
		(property "License" "Apache-2.0"
			(at 139.7 161.29 0)
			(effects
				(font
					(size 1.27 1.27)
					(thickness 0.15)
				)
				(justify left bottom)
				(hide yes)
			)
		)
		(property "Author" "Antmicro"
			(at 139.7 158.75 0)
			(effects
				(font
					(size 1.27 1.27)
					(thickness 0.15)
				)
				(justify left bottom)
				(hide yes)
			)
		)
		(property "Tolerance" "1%"
			(at 139.7 176.53 0)
			(effects
				(font
					(size 1.27 1.27)
				)
				(justify left bottom)
				(hide yes)
			)
		)
		(pin "1"
		)
		(pin "2"
		)
		(instances
			(project "jetson-agx-thor-baseboard"
				(path ""
					(reference "R279")
					(unit 1)
				)
			)
		)
	)
	(symbol
		(lib_id "antmicroResistors0402:R_0R_0402")
		(at 205.74 90.17 0)
		(unit 1)
		(exclude_from_sim no)
		(in_bom yes)
		(on_board yes)
		(dnp no)
		(property "Reference" "R339"
			(at 203.835 88.9 0)
			(effects
				(font
					(size 1.27 1.27)
					(thickness 0.15)
				)
			)
		)
		(property "Value" "R_0R_0402"
			(at 226.06 102.87 0)
			(effects
				(font
					(size 1.27 1.27)
					(thickness 0.15)
				)
				(justify left bottom)
				(hide yes)
			)
		)
		(property "Footprint" "antmicro-footprints:R_0402_1005Metric"
			(at 226.06 105.41 0)
			(effects
				(font
					(size 1.27 1.27)
					(thickness 0.15)
				)
				(justify left bottom)
				(hide yes)
			)
		)
		(property "Datasheet" "https://industrial.panasonic.com/cdbs/www-data/pdf/RDA0000/AOA0000C301.pdf"
			(at 226.06 107.95 0)
			(effects
				(font
					(size 1.27 1.27)
					(thickness 0.15)
				)
				(justify left bottom)
				(hide yes)
			)
		)
		(property "Description" "SMD Chip Resistor, Jumper, 0 ohm, 100 mW, 0402 [1005 Metric], Thick Film, General Purpose"
			(at 226.06 123.19 0)
			(effects
				(font
					(size 1.27 1.27)
				)
				(justify left bottom)
				(hide yes)
			)
		)
		(property "MPN" "ERJ2GE0R00X"
			(at 226.06 110.49 0)
			(effects
				(font
					(size 1.27 1.27)
					(thickness 0.15)
				)
				(justify left bottom)
				(hide yes)
			)
		)
		(property "Manufacturer" "Panasonic"
			(at 226.06 113.03 0)
			(effects
				(font
					(size 1.27 1.27)
					(thickness 0.15)
				)
				(justify left bottom)
				(hide yes)
			)
		)
		(property "License" "Apache-2.0"
			(at 226.06 115.57 0)
			(effects
				(font
					(size 1.27 1.27)
					(thickness 0.15)
				)
				(justify left bottom)
				(hide yes)
			)
		)
		(property "Author" "Antmicro"
			(at 226.06 118.11 0)
			(effects
				(font
					(size 1.27 1.27)
					(thickness 0.15)
				)
				(justify left bottom)
				(hide yes)
			)
		)
		(property "Val" "0R"
			(at 212.09 88.9 0)
			(effects
				(font
					(size 1.27 1.27)
					(thickness 0.15)
				)
			)
		)
		(property "Tolerance" "~"
			(at 226.06 100.33 0)
			(effects
				(font
					(size 1.27 1.27)
				)
				(justify left bottom)
				(hide yes)
			)
		)
		(property "Current" "1A"
			(at 226.06 120.65 0)
			(effects
				(font
					(size 1.27 1.27)
					(thickness 0.15)
				)
				(justify left bottom)
				(hide yes)
			)
		)
		(pin "1"
		)
		(pin "2"
		)
		(instances
			(project ""
				(path ""
					(reference "R339")
					(unit 1)
				)
			)
		)
	)
	(symbol
		(lib_id "antmicroResistors0402:R_10k_0402")
		(at 124.46 124.46 270)
		(unit 1)
		(exclude_from_sim no)
		(in_bom no)
		(on_board yes)
		(dnp yes)
		(property "Reference" "R254"
			(at 125.73 125.73 90)
			(effects
				(font
					(size 1.27 1.27)
				)
				(justify left)
			)
		)
		(property "Value" "R_10k_0402"
			(at 111.76 144.78 0)
			(effects
				(font
					(size 1.27 1.27)
					(thickness 0.15)
				)
				(justify left bottom)
				(hide yes)
			)
		)
		(property "Footprint" "antmicro-footprints:R_0402_1005Metric"
			(at 109.22 144.78 0)
			(effects
				(font
					(size 1.27 1.27)
					(thickness 0.15)
				)
				(justify left bottom)
				(hide yes)
			)
		)
		(property "Datasheet" "https://www.bourns.com/docs/product-datasheets/cr.pdf"
			(at 106.68 144.78 0)
			(effects
				(font
					(size 1.27 1.27)
					(thickness 0.15)
				)
				(justify left bottom)
				(hide yes)
			)
		)
		(property "Description" "SMD Chip Resistor, 10 kohm, ± 1%, 62.5 mW, 0402 [1005 Metric], Thick Film, General Purpose"
			(at 124.46 124.46 0)
			(effects
				(font
					(size 1.27 1.27)
				)
				(hide yes)
			)
		)
		(property "Manufacturer" "Bourns"
			(at 101.6 144.78 0)
			(effects
				(font
					(size 1.27 1.27)
					(thickness 0.15)
				)
				(justify left bottom)
				(hide yes)
			)
		)
		(property "MPN" "CR0402-FX-1002GLF"
			(at 104.14 144.78 0)
			(effects
				(font
					(size 1.27 1.27)
					(thickness 0.15)
				)
				(justify left bottom)
				(hide yes)
			)
		)
		(property "Val" "10k"
			(at 125.73 128.27 90)
			(effects
				(font
					(size 1.27 1.27)
					(thickness 0.15)
				)
				(justify left)
			)
		)
		(property "License" "Apache-2.0"
			(at 99.06 144.78 0)
			(effects
				(font
					(size 1.27 1.27)
					(thickness 0.15)
				)
				(justify left bottom)
				(hide yes)
			)
		)
		(property "Author" "Antmicro"
			(at 96.52 144.78 0)
			(effects
				(font
					(size 1.27 1.27)
					(thickness 0.15)
				)
				(justify left bottom)
				(hide yes)
			)
		)
		(property "Tolerance" "1%"
			(at 114.3 144.78 0)
			(effects
				(font
					(size 1.27 1.27)
				)
				(justify left bottom)
				(hide yes)
			)
		)
		(pin "1"
		)
		(pin "2"
		)
		(instances
			(project "jetson-agx-thor-baseboard"
				(path ""
					(reference "R254")
					(unit 1)
				)
			)
		)
	)
	(symbol
		(lib_id "antmicroCapacitors0402:C_100n_0402")
		(at 162.56 100.33 90)
		(mirror x)
		(unit 1)
		(exclude_from_sim no)
		(in_bom yes)
		(on_board yes)
		(dnp no)
		(fields_autoplaced yes)
		(property "Reference" "C232"
			(at 165.1 101.6063 90)
			(effects
				(font
					(size 1.27 1.27)
				)
				(justify right)
			)
		)
		(property "Value" "C_100n_0402"
			(at 172.72 120.65 0)
			(effects
				(font
					(size 1.27 1.27)
					(thickness 0.15)
				)
				(justify left bottom)
				(hide yes)
			)
		)
		(property "Footprint" "antmicro-footprints:C_0402_1005Metric"
			(at 175.26 120.65 0)
			(effects
				(font
					(size 1.27 1.27)
					(thickness 0.15)
				)
				(justify left bottom)
				(hide yes)
			)
		)
		(property "Datasheet" "https://www.murata.com/products/productdetail?partno=GRM155R61H104KE14%23"
			(at 177.8 120.65 0)
			(effects
				(font
					(size 1.27 1.27)
					(thickness 0.15)
				)
				(justify left bottom)
				(hide yes)
			)
		)
		(property "Description" "SMD Multilayer Ceramic Capacitor, 0.1 µF, 50 V, 0402 [1005 Metric], ± 10%, X5R, GRM Series"
			(at 162.56 100.33 0)
			(effects
				(font
					(size 1.27 1.27)
				)
				(hide yes)
			)
		)
		(property "Manufacturer" "Murata"
			(at 182.88 120.65 0)
			(effects
				(font
					(size 1.27 1.27)
					(thickness 0.15)
				)
				(justify left bottom)
				(hide yes)
			)
		)
		(property "MPN" "GRM155R61H104KE14D"
			(at 180.34 120.65 0)
			(effects
				(font
					(size 1.27 1.27)
					(thickness 0.15)
				)
				(justify left bottom)
				(hide yes)
			)
		)
		(property "Val" "100n"
			(at 165.1 104.1463 90)
			(effects
				(font
					(size 1.27 1.27)
					(thickness 0.15)
				)
				(justify right)
			)
		)
		(property "License" "Apache-2.0"
			(at 185.42 120.65 0)
			(effects
				(font
					(size 1.27 1.27)
					(thickness 0.15)
				)
				(justify left bottom)
				(hide yes)
			)
		)
		(property "Author" "Antmicro"
			(at 187.96 120.65 0)
			(effects
				(font
					(size 1.27 1.27)
					(thickness 0.15)
				)
				(justify left bottom)
				(hide yes)
			)
		)
		(property "Voltage" "50V"
			(at 190.5 120.65 0)
			(effects
				(font
					(size 1.27 1.27)
				)
				(justify left bottom)
				(hide yes)
			)
		)
		(property "Dielectric" "X5R"
			(at 193.04 120.65 0)
			(effects
				(font
					(size 1.27 1.27)
				)
				(justify left bottom)
				(hide yes)
			)
		)
		(pin "1"
		)
		(pin "2"
		)
		(instances
			(project "jetson-agx-thor-baseboard"
				(path ""
					(reference "C232")
					(unit 1)
				)
			)
		)
	)
	(symbol
		(lib_id "antmicroTVSDiodes:PESD5Z5_0F")
		(at 302.26 86.36 270)
		(unit 1)
		(exclude_from_sim no)
		(in_bom yes)
		(on_board yes)
		(dnp no)
		(property "Reference" "D50"
			(at 303.53 87.63 90)
			(effects
				(font
					(size 1.27 1.27)
				)
				(justify left)
			)
		)
		(property "Value" "PESD5Z5.0F"
			(at 287.02 107.95 0)
			(effects
				(font
					(size 1.27 1.27)
					(thickness 0.15)
				)
				(justify left bottom)
				(hide yes)
			)
		)
		(property "Footprint" "antmicro-footprints:SOD-523"
			(at 297.18 101.6 0)
			(effects
				(font
					(size 1.27 1.27)
					(thickness 0.15)
				)
				(justify left bottom)
				(hide yes)
			)
		)
		(property "Datasheet" "https://assets.nexperia.com/documents/data-sheet/PESD5Z5_0.pdf"
			(at 294.64 101.6 0)
			(effects
				(font
					(size 1.27 1.27)
					(thickness 0.15)
				)
				(justify left bottom)
				(hide yes)
			)
		)
		(property "Description" "Unidirectional TVS, 30 kV,  SOD-523, 5 V, 89 pF"
			(at 281.94 101.6 0)
			(effects
				(font
					(size 1.27 1.27)
				)
				(justify left bottom)
				(hide yes)
			)
		)
		(property "Manufacturer" "Nexperia"
			(at 292.1 101.6 0)
			(effects
				(font
					(size 1.27 1.27)
					(thickness 0.15)
				)
				(justify left bottom)
				(hide yes)
			)
		)
		(property "MPN" "PESD5Z5.0F"
			(at 303.784 90.424 90)
			(effects
				(font
					(size 1.27 1.27)
					(thickness 0.15)
				)
				(justify left bottom)
			)
		)
		(property "Author" "Antmicro"
			(at 287.02 101.6 0)
			(effects
				(font
					(size 1.27 1.27)
					(thickness 0.15)
				)
				(justify left bottom)
				(hide yes)
			)
		)
		(property "License" "Apache-2.0"
			(at 284.48 101.6 0)
			(effects
				(font
					(size 1.27 1.27)
					(thickness 0.15)
				)
				(justify left bottom)
				(hide yes)
			)
		)
		(pin "1"
		)
		(pin "2"
		)
		(instances
			(project "jetson-agx-thor-baseboard"
				(path ""
					(reference "D50")
					(unit 1)
				)
			)
		)
	)
	(symbol
		(lib_id "antmicroTestPoints:TP_0.75mm_SMD")
		(at 311.15 82.55 90)
		(unit 1)
		(exclude_from_sim no)
		(in_bom no)
		(on_board yes)
		(dnp no)
		(property "Reference" "TP47"
			(at 313.182 77.47 90)
			(effects
				(font
					(size 1.27 1.27)
				)
				(justify left)
			)
		)
		(property "Value" "TP_0.75mm_SMD"
			(at 314.96 72.39 0)
			(effects
				(font
					(size 1.27 1.27)
					(thickness 0.15)
				)
				(justify left bottom)
				(hide yes)
			)
		)
		(property "Footprint" "antmicro-footprints:TP_SMD_0.75mm"
			(at 317.5 72.39 0)
			(effects
				(font
					(size 1.27 1.27)
					(thickness 0.15)
				)
				(justify left bottom)
				(hide yes)
			)
		)
		(property "Datasheet" ""
			(at 323.85 64.77 0)
			(effects
				(font
					(size 1.27 1.27)
					(thickness 0.15)
				)
				(justify left bottom)
				(hide yes)
			)
		)
		(property "Description" "SMT test point"
			(at 311.15 82.55 0)
			(effects
				(font
					(size 1.27 1.27)
				)
				(hide yes)
			)
		)
		(property "MPN" ""
			(at 322.58 71.755 0)
			(effects
				(font
					(size 1.27 1.27)
					(thickness 0.15)
				)
				(justify left bottom)
				(hide yes)
			)
		)
		(property "Manufacturer" ""
			(at 317.5 71.755 0)
			(effects
				(font
					(size 1.27 1.27)
					(thickness 0.15)
				)
				(justify left bottom)
				(hide yes)
			)
		)
		(property "Author" "Antmicro"
			(at 320.04 72.39 0)
			(effects
				(font
					(size 1.27 1.27)
					(thickness 0.15)
				)
				(justify left bottom)
				(hide yes)
			)
		)
		(property "License" "Apache-2.0"
			(at 322.58 72.39 0)
			(effects
				(font
					(size 1.27 1.27)
					(thickness 0.15)
				)
				(justify left bottom)
				(hide yes)
			)
		)
		(pin "1"
		)
		(instances
			(project "jetson-agx-thor-baseboard"
				(path ""
					(reference "TP47")
					(unit 1)
				)
			)
		)
	)
	(symbol
		(lib_id "antmicropower:GND")
		(at 337.82 93.98 0)
		(unit 1)
		(exclude_from_sim no)
		(in_bom yes)
		(on_board yes)
		(dnp no)
		(property "Reference" "#PWR0482"
			(at 337.82 100.33 0)
			(effects
				(font
					(size 1.27 1.27)
				)
				(justify left bottom)
				(hide yes)
			)
		)
		(property "Value" "GND"
			(at 337.82 97.79 0)
			(effects
				(font
					(size 1.27 1.27)
					(thickness 0.15)
				)
			)
		)
		(property "Footprint" ""
			(at 346.71 101.6 0)
			(effects
				(font
					(size 1.27 1.27)
					(thickness 0.15)
				)
				(justify left bottom)
				(hide yes)
			)
		)
		(property "Datasheet" ""
			(at 346.71 106.68 0)
			(effects
				(font
					(size 1.27 1.27)
					(thickness 0.15)
				)
				(justify left bottom)
				(hide yes)
			)
		)
		(property "Description" ""
			(at 337.82 93.98 0)
			(effects
				(font
					(size 1.27 1.27)
				)
				(hide yes)
			)
		)
		(property "Author" "Antmicro"
			(at 346.71 101.6 0)
			(effects
				(font
					(size 1.27 1.27)
					(thickness 0.15)
				)
				(justify left bottom)
				(hide yes)
			)
		)
		(property "License" "Apache-2.0"
			(at 346.71 104.14 0)
			(effects
				(font
					(size 1.27 1.27)
					(thickness 0.15)
				)
				(justify left bottom)
				(hide yes)
			)
		)
		(pin "1"
		)
		(instances
			(project "jetson-agx-thor-baseboard"
				(path ""
					(reference "#PWR0482")
					(unit 1)
				)
			)
		)
	)
	(symbol
		(lib_id "antmicropower:GND")
		(at 279.4 92.71 0)
		(unit 1)
		(exclude_from_sim no)
		(in_bom yes)
		(on_board yes)
		(dnp no)
		(fields_autoplaced yes)
		(property "Reference" "#PWR0475"
			(at 279.4 99.06 0)
			(effects
				(font
					(size 1.27 1.27)
				)
				(justify left bottom)
				(hide yes)
			)
		)
		(property "Value" "GND"
			(at 279.4 96.52 0)
			(effects
				(font
					(size 1.27 1.27)
					(thickness 0.15)
				)
			)
		)
		(property "Footprint" ""
			(at 288.29 100.33 0)
			(effects
				(font
					(size 1.27 1.27)
					(thickness 0.15)
				)
				(justify left bottom)
				(hide yes)
			)
		)
		(property "Datasheet" ""
			(at 288.29 105.41 0)
			(effects
				(font
					(size 1.27 1.27)
					(thickness 0.15)
				)
				(justify left bottom)
				(hide yes)
			)
		)
		(property "Description" ""
			(at 279.4 92.71 0)
			(effects
				(font
					(size 1.27 1.27)
				)
				(hide yes)
			)
		)
		(property "Author" "Antmicro"
			(at 288.29 100.33 0)
			(effects
				(font
					(size 1.27 1.27)
					(thickness 0.15)
				)
				(justify left bottom)
				(hide yes)
			)
		)
		(property "License" "Apache-2.0"
			(at 288.29 102.87 0)
			(effects
				(font
					(size 1.27 1.27)
					(thickness 0.15)
				)
				(justify left bottom)
				(hide yes)
			)
		)
		(pin "1"
		)
		(instances
			(project "jetson-agx-thor-baseboard"
				(path ""
					(reference "#PWR0475")
					(unit 1)
				)
			)
		)
	)
	(symbol
		(lib_id "antmicroResistors0402:R_887k_0402")
		(at 219.71 127 0)
		(unit 1)
		(exclude_from_sim no)
		(in_bom yes)
		(on_board yes)
		(dnp no)
		(property "Reference" "R267"
			(at 224.79 126.365 0)
			(effects
				(font
					(size 1.27 1.27)
					(thickness 0.15)
				)
				(justify left bottom)
			)
		)
		(property "Value" "R_887k_0402"
			(at 240.03 139.7 0)
			(effects
				(font
					(size 1.27 1.27)
					(thickness 0.15)
				)
				(justify left bottom)
				(hide yes)
			)
		)
		(property "Footprint" "antmicro-footprints:R_0402_1005Metric"
			(at 240.03 142.24 0)
			(effects
				(font
					(size 1.27 1.27)
					(thickness 0.15)
				)
				(justify left bottom)
				(hide yes)
			)
		)
		(property "Datasheet" "https://eu.mouser.com/datasheet/2/315/AOA0000C304-1149620.pdf"
			(at 240.03 144.78 0)
			(effects
				(font
					(size 1.27 1.27)
					(thickness 0.15)
				)
				(justify left bottom)
				(hide yes)
			)
		)
		(property "Description" "SMD Chip Resistor"
			(at 219.71 127 0)
			(effects
				(font
					(size 1.27 1.27)
				)
				(hide yes)
			)
		)
		(property "MPN" "ERJ-2RKF8873X"
			(at 240.03 147.32 0)
			(effects
				(font
					(size 1.27 1.27)
					(thickness 0.15)
				)
				(justify left bottom)
				(hide yes)
			)
		)
		(property "Manufacturer" "Panasonic"
			(at 240.03 149.86 0)
			(effects
				(font
					(size 1.27 1.27)
					(thickness 0.15)
				)
				(justify left bottom)
				(hide yes)
			)
		)
		(property "License" "Apache-2.0"
			(at 240.03 152.4 0)
			(effects
				(font
					(size 1.27 1.27)
					(thickness 0.15)
				)
				(justify left bottom)
				(hide yes)
			)
		)
		(property "Author" "Antmicro"
			(at 240.03 154.94 0)
			(effects
				(font
					(size 1.27 1.27)
					(thickness 0.15)
				)
				(justify left bottom)
				(hide yes)
			)
		)
		(property "Val" "887k"
			(at 214.63 126.365 0)
			(effects
				(font
					(size 1.27 1.27)
					(thickness 0.15)
				)
				(justify left bottom)
			)
		)
		(property "Tolerance" "1%"
			(at 240.03 137.16 0)
			(effects
				(font
					(size 1.27 1.27)
				)
				(justify left bottom)
				(hide yes)
			)
		)
		(pin "2"
		)
		(pin "1"
		)
		(instances
			(project "jetson-agx-thor-baseboard"
				(path ""
					(reference "R267")
					(unit 1)
				)
			)
		)
	)
	(symbol
		(lib_id "antmicropower:+3V3")
		(at 113.03 184.15 0)
		(unit 1)
		(exclude_from_sim no)
		(in_bom yes)
		(on_board yes)
		(dnp no)
		(property "Reference" "#PWR0454"
			(at 113.03 187.96 0)
			(effects
				(font
					(size 1.27 1.27)
				)
				(justify left bottom)
				(hide yes)
			)
		)
		(property "Value" "+3V3"
			(at 116.205 180.34 0)
			(effects
				(font
					(size 1.27 1.27)
					(thickness 0.15)
				)
				(justify right)
			)
		)
		(property "Footprint" ""
			(at 128.27 191.77 0)
			(effects
				(font
					(size 1.27 1.27)
					(thickness 0.15)
				)
				(justify left bottom)
				(hide yes)
			)
		)
		(property "Datasheet" ""
			(at 128.27 194.31 0)
			(effects
				(font
					(size 1.27 1.27)
					(thickness 0.15)
				)
				(justify left bottom)
				(hide yes)
			)
		)
		(property "Description" ""
			(at 113.03 184.15 0)
			(effects
				(font
					(size 1.27 1.27)
				)
				(hide yes)
			)
		)
		(property "Author" "Antmicro"
			(at 128.27 186.69 0)
			(effects
				(font
					(size 1.27 1.27)
					(thickness 0.15)
				)
				(justify left bottom)
				(hide yes)
			)
		)
		(property "License" "Apache-2.0"
			(at 128.27 189.23 0)
			(effects
				(font
					(size 1.27 1.27)
					(thickness 0.15)
				)
				(justify left bottom)
				(hide yes)
			)
		)
		(pin "1"
		)
		(instances
			(project "jetson-agx-thor-baseboard"
				(path ""
					(reference "#PWR0454")
					(unit 1)
				)
			)
		)
	)
	(symbol
		(lib_id "antmicroCapacitors0402:C_100n_0402")
		(at 222.25 162.56 180)
		(unit 1)
		(exclude_from_sim no)
		(in_bom yes)
		(on_board yes)
		(dnp no)
		(property "Reference" "C109"
			(at 226.06 160.528 0)
			(effects
				(font
					(size 1.27 1.27)
				)
				(justify left bottom)
			)
		)
		(property "Value" "C_100n_0402"
			(at 201.93 152.4 0)
			(effects
				(font
					(size 1.27 1.27)
					(thickness 0.15)
				)
				(justify left bottom)
				(hide yes)
			)
		)
		(property "Footprint" "antmicro-footprints:C_0402_1005Metric"
			(at 201.93 149.86 0)
			(effects
				(font
					(size 1.27 1.27)
					(thickness 0.15)
				)
				(justify left bottom)
				(hide yes)
			)
		)
		(property "Datasheet" "https://www.murata.com/products/productdetail?partno=GRM155R61H104KE14%23"
			(at 201.93 147.32 0)
			(effects
				(font
					(size 1.27 1.27)
					(thickness 0.15)
				)
				(justify left bottom)
				(hide yes)
			)
		)
		(property "Description" "SMD Multilayer Ceramic Capacitor, 0.1 µF, 50 V, 0402 [1005 Metric], ± 10%, X5R, GRM Series"
			(at 222.25 162.56 0)
			(effects
				(font
					(size 1.27 1.27)
				)
				(hide yes)
			)
		)
		(property "Manufacturer" "Murata"
			(at 201.93 142.24 0)
			(effects
				(font
					(size 1.27 1.27)
					(thickness 0.15)
				)
				(justify left bottom)
				(hide yes)
			)
		)
		(property "MPN" "GRM155R61H104KE14D"
			(at 201.93 144.78 0)
			(effects
				(font
					(size 1.27 1.27)
					(thickness 0.15)
				)
				(justify left bottom)
				(hide yes)
			)
		)
		(property "Val" "100n"
			(at 218.44 163.195 0)
			(effects
				(font
					(size 1.27 1.27)
					(thickness 0.15)
				)
				(justify left bottom)
			)
		)
		(property "License" "Apache-2.0"
			(at 201.93 139.7 0)
			(effects
				(font
					(size 1.27 1.27)
					(thickness 0.15)
				)
				(justify left bottom)
				(hide yes)
			)
		)
		(property "Author" "Antmicro"
			(at 201.93 137.16 0)
			(effects
				(font
					(size 1.27 1.27)
					(thickness 0.15)
				)
				(justify left bottom)
				(hide yes)
			)
		)
		(property "Voltage" "50V"
			(at 201.93 134.62 0)
			(effects
				(font
					(size 1.27 1.27)
				)
				(justify left bottom)
				(hide yes)
			)
		)
		(property "Dielectric" "X5R"
			(at 201.93 132.08 0)
			(effects
				(font
					(size 1.27 1.27)
				)
				(justify left bottom)
				(hide yes)
			)
		)
		(pin "1"
		)
		(pin "2"
		)
		(instances
			(project "jetson-agx-thor-baseboard"
				(path ""
					(reference "C109")
					(unit 1)
				)
			)
		)
	)
	(symbol
		(lib_id "antmicroCapacitors0402:C_100n_0402")
		(at 237.49 73.66 90)
		(mirror x)
		(unit 1)
		(exclude_from_sim no)
		(in_bom yes)
		(on_board yes)
		(dnp no)
		(fields_autoplaced yes)
		(property "Reference" "C114"
			(at 240.03 74.9363 90)
			(effects
				(font
					(size 1.27 1.27)
				)
				(justify right)
			)
		)
		(property "Value" "C_100n_0402"
			(at 247.65 93.98 0)
			(effects
				(font
					(size 1.27 1.27)
					(thickness 0.15)
				)
				(justify left bottom)
				(hide yes)
			)
		)
		(property "Footprint" "antmicro-footprints:C_0402_1005Metric"
			(at 250.19 93.98 0)
			(effects
				(font
					(size 1.27 1.27)
					(thickness 0.15)
				)
				(justify left bottom)
				(hide yes)
			)
		)
		(property "Datasheet" "https://www.murata.com/products/productdetail?partno=GRM155R61H104KE14%23"
			(at 252.73 93.98 0)
			(effects
				(font
					(size 1.27 1.27)
					(thickness 0.15)
				)
				(justify left bottom)
				(hide yes)
			)
		)
		(property "Description" "SMD Multilayer Ceramic Capacitor, 0.1 µF, 50 V, 0402 [1005 Metric], ± 10%, X5R, GRM Series"
			(at 237.49 73.66 0)
			(effects
				(font
					(size 1.27 1.27)
				)
				(hide yes)
			)
		)
		(property "Manufacturer" "Murata"
			(at 257.81 93.98 0)
			(effects
				(font
					(size 1.27 1.27)
					(thickness 0.15)
				)
				(justify left bottom)
				(hide yes)
			)
		)
		(property "MPN" "GRM155R61H104KE14D"
			(at 255.27 93.98 0)
			(effects
				(font
					(size 1.27 1.27)
					(thickness 0.15)
				)
				(justify left bottom)
				(hide yes)
			)
		)
		(property "Val" "100n"
			(at 240.03 77.4763 90)
			(effects
				(font
					(size 1.27 1.27)
					(thickness 0.15)
				)
				(justify right)
			)
		)
		(property "License" "Apache-2.0"
			(at 260.35 93.98 0)
			(effects
				(font
					(size 1.27 1.27)
					(thickness 0.15)
				)
				(justify left bottom)
				(hide yes)
			)
		)
		(property "Author" "Antmicro"
			(at 262.89 93.98 0)
			(effects
				(font
					(size 1.27 1.27)
					(thickness 0.15)
				)
				(justify left bottom)
				(hide yes)
			)
		)
		(property "Voltage" "50V"
			(at 265.43 93.98 0)
			(effects
				(font
					(size 1.27 1.27)
				)
				(justify left bottom)
				(hide yes)
			)
		)
		(property "Dielectric" "X5R"
			(at 267.97 93.98 0)
			(effects
				(font
					(size 1.27 1.27)
				)
				(justify left bottom)
				(hide yes)
			)
		)
		(pin "1"
		)
		(pin "2"
		)
		(instances
			(project "jetson-agx-thor-baseboard"
				(path ""
					(reference "C114")
					(unit 1)
				)
			)
		)
	)
)
